G04 ================== begin FILE IDENTIFICATION RECORD ==================*
G04 Layout Name:  13130-1b.brd*
G04 Film Name:    L3*
G04 File Format:  Gerber RS274X*
G04 File Origin:  Cadence Allegro 16.5-S037*
G04 Origin Date:  Thu Nov 13 17:26:54 2014*
G04 *
G04 Layer:  VIA CLASS/L3*
G04 Layer:  PIN/L3*
G04 Layer:  ETCH/L3*
G04 Layer:  DRAWING FORMAT/LAYER_PCB_STORY*
G04 Layer:  DRAWING FORMAT/LAYER_L3*
G04 *
G04 Offset:    (0.00 0.00)*
G04 Mirror:    No*
G04 Mode:      Positive*
G04 Rotation:  0*
G04 FullContactRelief:  No*
G04 UndefLineWidth:     6.00*
G04 ================== end FILE IDENTIFICATION RECORD ====================*
%FSLAX35Y35*MOIN*%
%IR0*IPPOS*OFA0.00000B0.00000*MIA0B0*SFA1.00000B1.00000*%
%ADD11C,.02*%
%ADD12C,.022*%
%ADD13C,.017*%
%ADD10C,.028*%
%ADD14C,.056*%
%ADD15C,.01*%
%ADD16C,.011*%
%ADD17C,.012*%
%ADD18C,.04*%
%ADD19C,.015*%
%ADD20C,.025*%
%ADD21C,.018*%
%ADD22C,.004*%
%ADD23C,.006*%
%ADD24C,.005*%
%ADD25C,.008*%
%ADD26C,.0035*%
%ADD27C,.0045*%
%ADD32C,.03004*%
%ADD31C,.05204*%
%ADD33C,.08004*%
%ADD30C,.04404*%
%ADD34C,.02704*%
%ADD37C,.04604*%
%ADD38C,.08404*%
%ADD35C,.06804*%
%ADD36C,.09176*%
%ADD28C,.11004*%
%ADD29C,.15004*%
G75*
%LPD*%
G75*
G36*
G01X4000Y61000D02*
X3500Y61500D01*
Y112500D01*
X4500Y113500D01*
X18500D01*
X32500Y127500D01*
Y143783D01*
G03Y146217I-2300J1217D01*
G01Y147983D01*
G03Y150417I-2300J1217D01*
G01Y152183D01*
G03Y154617I-2300J1217D01*
G01Y156211D01*
G03X32744Y158493I-2200J1389D01*
G02X33237Y159012I376J137D01*
G03X33047Y163921I763J2488D01*
G02X32500Y164293I-147J372D01*
G01Y170500D01*
X34500Y172500D01*
Y176138D01*
G03X35697Y178253I-1000J1962D01*
G01X35690Y178344D01*
X36620Y179274D01*
X41054D01*
G02X41287Y178549I0J-400D01*
G03X50051I4382J-6089D01*
G02X50284Y179274I233J325D01*
G01X56994D01*
G02X57272Y178586I0J-400D01*
G03X60328I1528J-1586D01*
G02X60606Y179274I278J288D01*
G01X79331D01*
G02X79686Y178691I-1J-400D01*
G03X84314I2314J-1191D01*
G02X84669Y179274I356J183D01*
G01X96920D01*
X107647Y190000D01*
X108500D01*
X109500Y189000D01*
Y141500D01*
X111000Y140000D01*
X121000D01*
X121498Y139502D01*
Y138498D01*
X121000Y138000D01*
X119500D01*
X118500Y137000D01*
Y135590D01*
G03Y135410I2200J-90D01*
G01Y132000D01*
X112500Y126000D01*
Y95500D01*
X95500Y78500D01*
X85000D01*
X67500Y61000D01*
X4000D01*
G37*
G36*
G01X23100Y179598D02*
G02X23500Y179198I0J-400D01*
G01Y170500D01*
X26000Y168000D01*
Y124400D01*
X17500Y115900D01*
X5000D01*
X3001Y117899D01*
Y217501D01*
X13500Y228000D01*
X15515D01*
X15541Y227993D01*
G03X16695I577J2125D01*
G01X16721Y228000D01*
X17500D01*
X19500Y230000D01*
Y271900D01*
X35000Y287400D01*
X112100D01*
X112500Y287000D01*
Y284500D01*
X112101Y284102D01*
X107637D01*
X107535Y284000D01*
X107000D01*
X100400Y277400D01*
X79468D01*
G03X76932I-1268J-1800D01*
G01X69500D01*
X68400Y278500D01*
X43000D01*
X35000Y270500D01*
Y264722D01*
X34993Y264696D01*
G03Y263304I2507J-696D01*
G01X35000Y263278D01*
Y220000D01*
X26000Y211000D01*
Y186647D01*
X23344Y183990D01*
X23253Y183997D01*
G03X23100Y179598I-153J-2197D01*
G37*
G36*
G01X18000Y230199D02*
X17002Y229202D01*
X13002D01*
X12801Y229000D01*
X12500D01*
X5000Y221500D01*
X3500D01*
X3000Y222000D01*
Y229498D01*
X3001Y229499D01*
Y286501D01*
X4000Y287500D01*
X27500D01*
X28500Y286500D01*
Y283000D01*
X18000Y272500D01*
Y271506D01*
G02X17492Y271121I-400J0D01*
G03Y266879I-592J-2121D01*
G02X18000Y266494I108J-385D01*
G01Y230199D01*
G37*
G36*
G01X30000Y194000D02*
X27500Y196500D01*
Y210500D01*
X34000Y217000D01*
X38500D01*
X39500Y218000D01*
Y235701D01*
X39522Y236460D01*
X39512D01*
Y236502D01*
X39500D01*
Y236508D01*
X39512D01*
Y236510D01*
G03X39500Y236694I-1512J-6D01*
G01Y249701D01*
X39522Y250460D01*
X39512D01*
Y250502D01*
X39500D01*
Y250508D01*
X39512D01*
Y250510D01*
G03X39500Y250694I-1512J-6D01*
G01Y260000D01*
X40500Y261000D01*
X41500D01*
X42500Y260000D01*
Y251513D01*
G03X44308Y248200I1900J-1113D01*
G02X44500Y248000I-8J-200D01*
G01Y236500D01*
X48000Y233000D01*
Y216447D01*
X46398Y214845D01*
Y195305D01*
G02X45728Y195011I-400J0D01*
G03X40597Y195646I-3011J-3279D01*
G02X40021Y195891I-190J352D01*
G03X38905Y197259I-2121J-591D01*
G02X38775Y197864I183J356D01*
G03X36601Y197678I-1175J936D01*
G02X36576Y197060I-266J-299D01*
G03X36240Y196746I1327J-1757D01*
G02X35563Y196869I-302J263D01*
G03X33754Y198287I-2063J-769D01*
G02X33421Y198814I46J398D01*
G03X33502Y199336I-1421J488D01*
G01Y203164D01*
G03X30498I-1502J36D01*
G01Y199336D01*
G03X31464Y197897I1502J-36D01*
G02X31657Y197304I-142J-374D01*
G03X31833Y194661I1843J-1205D01*
G02X31530Y194000I-303J-261D01*
G01X30000D01*
G37*
G36*
G01X47610Y183876D02*
G02X47327Y184559I0J400D01*
G01X49857Y187089D01*
G02X50500Y186981I283J-283D01*
G03X53362Y187471I1360J659D01*
G01X53372Y187555D01*
Y191420D01*
G03X51616Y192902I-1512J-10D01*
G02X51152Y193296I-64J394D01*
G01Y194784D01*
X52868Y196500D01*
X56000D01*
X61500Y191000D01*
X72590D01*
X72606Y190817D01*
G03X74461Y193176I2194J183D01*
G02X74000Y193571I-61J395D01*
G01Y199000D01*
X70500Y202500D01*
Y239500D01*
X65500Y244500D01*
Y263500D01*
X66500Y264500D01*
X71000D01*
X72000Y263500D01*
Y259000D01*
X73500Y257500D01*
X81437D01*
X81465Y257492D01*
G03X82735I635J2108D01*
G01X82763Y257500D01*
X83000D01*
X83182Y257682D01*
G03X84018Y258518I-1082J1918D01*
G01X86500Y261000D01*
Y268500D01*
X90000Y272000D01*
X93500D01*
X94500Y271000D01*
Y246500D01*
X94898Y246102D01*
Y246088D01*
X96043Y244943D01*
G03X96188Y244811I1553J1560D01*
G01X96194Y244806D01*
X96500Y244500D01*
X96679D01*
X96717Y244483D01*
G03X98520Y244500I883J2017D01*
G01X104000D01*
X112000Y252500D01*
Y266987D01*
X114312Y269298D01*
X124588D01*
X126462Y267425D01*
X126475Y267371D01*
G03X129515Y265450I2525J629D01*
G02X129994Y265057I79J-392D01*
G01Y256108D01*
X128925Y255038D01*
X128871Y255025D01*
G03X132025Y251871I629J-2525D01*
G01X132038Y251925D01*
X134398Y254284D01*
Y270242D01*
X134000Y270639D01*
Y272500D01*
X135500Y274000D01*
X137500D01*
X142500Y269000D01*
X142800D01*
X142854Y268958D01*
G03X145599Y269000I1346J1742D01*
G01X177500D01*
X184000Y262500D01*
X204500D01*
X209000Y258000D01*
Y251500D01*
X210500Y250000D01*
X220000D01*
X224000Y254000D01*
Y256500D01*
X219500Y261000D01*
X217000D01*
X208500Y269500D01*
X186500D01*
X176000Y280000D01*
Y286500D01*
X177000Y287500D01*
X193147D01*
G02X193486Y286887I0J-400D01*
G03X206908I6711J-4210D01*
G02X207247Y287500I339J213D01*
G01X243000D01*
X244000Y286500D01*
Y257000D01*
X243000Y256000D01*
X232000D01*
X221000Y245000D01*
Y224500D01*
X218500Y222000D01*
X208000D01*
X206500Y220500D01*
X151000D01*
X150000Y221500D01*
Y236500D01*
X151500Y238000D01*
X167500D01*
X169000Y239500D01*
Y240278D01*
X169007Y240304D01*
G03Y241696I-2507J696D01*
G01X169000Y241722D01*
Y242500D01*
X168000Y243500D01*
X167222D01*
X167196Y243507D01*
G03X165804I-696J-2507D01*
G01X165778Y243500D01*
X140000D01*
X139952Y243452D01*
X139485D01*
X123885Y227852D01*
X121648D01*
X121000Y228500D01*
X112000D01*
X109500Y226000D01*
Y214500D01*
X105062Y210062D01*
X104768D01*
X100398Y205692D01*
Y204802D01*
X94954D01*
G03X91338Y205560I-2054J-794D01*
G02X91055Y205559I-142J141D01*
G03X87858Y202533I-1554J-1560D01*
G01X87909Y202476D01*
Y202200D01*
X87411D01*
X87354Y202249D01*
G03X83925Y199620I-1456J-1652D01*
G02X83741Y199082I-358J-178D01*
G03X86673Y198078I959J-1982D01*
G02X86857Y198616I358J178D01*
G03X87409Y198996I-958J1983D01*
G01X93261D01*
X95863Y201598D01*
X100489D01*
G03X101000Y201238I1511J1602D01*
G01Y195365D01*
X97038Y191402D01*
X96962Y191398D01*
G03X97159Y186999I137J-2198D01*
G02X97452Y186316I11J-400D01*
G01X95013Y183876D01*
X61288D01*
G02X60890Y184229I0J400D01*
G01Y184390D01*
G03X59379Y185892I-1511J-9D01*
G01X55720D01*
G03X54211Y184298I0J-1511D01*
G02X53811Y183876I-400J-22D01*
G01X47610D01*
G37*
G36*
G01X49502Y270500D02*
X50500Y271498D01*
X58002D01*
X64000Y265500D01*
Y243500D01*
X69000Y238500D01*
Y202000D01*
X72500Y198500D01*
Y193500D01*
X71500Y192500D01*
X62000D01*
X53500Y201000D01*
Y235000D01*
X49552Y238948D01*
Y265301D01*
X49502Y265351D01*
Y270500D01*
G37*
G36*
G01X129000Y156500D02*
X128838Y156662D01*
G02X128826Y157215I283J283D01*
G03X128000Y160752I-1626J1485D01*
G01Y161000D01*
X129682Y162682D01*
X129709Y162696D01*
G03X130804Y163791I-1209J2304D01*
G01X130818Y163818D01*
X135500Y168500D01*
Y168745D01*
X135602Y168847D01*
Y184102D01*
X141000Y189500D01*
X148000D01*
X168396Y209896D01*
X173224D01*
G02X173457Y209171I0J-400D01*
G03X176021I1282J-1790D01*
G02X176254Y209896I233J325D01*
G01X176391D01*
X176619Y209942D01*
G03X176881Y210011I-454J2256D01*
G01X176911Y210020D01*
X181480D01*
X182000Y209500D01*
Y205000D01*
X181676Y204676D01*
X181675D01*
X180500Y203502D01*
X173004D01*
X173002Y203500D01*
X173000D01*
X160000Y190500D01*
Y190498D01*
X159998Y190496D01*
Y179998D01*
X150500Y170500D01*
Y169981D01*
X150448Y169929D01*
Y165456D01*
X149494Y164502D01*
X144455D01*
X144453Y164500D01*
X139000D01*
X134000Y159500D01*
Y157500D01*
X133000Y156500D01*
X129000D01*
G37*
G36*
G01X173368Y192168D02*
X169850Y188650D01*
Y188500D01*
X169000Y187650D01*
Y183500D01*
G03X168000Y180180I800J-2052D01*
G01Y178500D01*
X167752Y178252D01*
X163248D01*
X162752Y178748D01*
Y189356D01*
X174144Y200748D01*
X181640D01*
X182815Y201924D01*
X196495D01*
X198838Y204267D01*
X198884Y204281D01*
G03X200386Y206124I-686J2093D01*
G01X200394Y206194D01*
X201650Y207450D01*
X205650D01*
X206242Y206858D01*
X206182Y206798D01*
Y206335D01*
X198999Y199152D01*
X193080D01*
X188428Y194500D01*
X186487D01*
G03X184605I-941J-1991D01*
G01X181487D01*
G03X179605I-941J-1991D01*
G01X176487D01*
G03X173358Y192264I-941J-1991D01*
G01X173368Y192168D01*
G37*
G36*
G01X214000Y94000D02*
X219550Y99550D01*
Y102950D01*
X219600Y103000D01*
Y105671D01*
X219640Y105710D01*
Y131540D01*
X223100Y135000D01*
X227500D01*
X228500Y134000D01*
Y132000D01*
X226000Y129500D01*
Y109225D01*
G03Y107383I2000J-921D01*
G01Y105723D01*
G03X225974Y103521I1894J-1124D01*
G01X226000Y103476D01*
Y102468D01*
G03Y99932I1800J-1268D01*
G01Y98769D01*
G03X225805Y96759I1850J-1194D01*
G02X225692Y96499I-186J-74D01*
G03X224370Y95009I808J-2049D01*
G01X224356Y94956D01*
X220400Y91000D01*
Y76100D01*
X205400Y61100D01*
X195900D01*
X195000Y62000D01*
Y66000D01*
X195795Y66795D01*
G03X198300Y67000I1105J1905D01*
G01X201100D01*
X214000Y79900D01*
Y84100D01*
G03Y86900I-1700J1400D01*
G01Y94000D01*
G37*
G36*
G01X251000Y268994D02*
X255191Y273186D01*
X263064D01*
X264801Y271449D01*
X264799Y271363D01*
G03X269151Y270828I2201J-63D01*
G01X269185Y270986D01*
X281514D01*
X285500Y267000D01*
X288500D01*
X292486Y270986D01*
X303514D01*
X306960Y267540D01*
X306919Y267421D01*
G03X311171Y266333I2081J-721D01*
G01X311199Y266500D01*
X312500D01*
X318492Y272492D01*
X344508D01*
X345500Y271500D01*
Y268000D01*
X333000Y255500D01*
X327700D01*
G03X324566Y255771I-1700J-1400D01*
G02X324028Y255786I-261J303D01*
G03X321019Y255830I-1528J-1586D01*
G02X320481I-269J296D01*
G03X317472Y255786I-1481J-1630D01*
G02X316934Y255771I-277J288D01*
G03X313800Y255500I-1434J-1671D01*
G01X310513D01*
G03X308287I-1113J-1900D01*
G01X307113D01*
G03X304887I-1113J-1900D01*
G01X303713D01*
G03X300457Y253092I-1113J-1900D01*
G01X300483Y252983D01*
X300001Y252502D01*
X298498D01*
X297695Y253305D01*
X297699Y253393D01*
G03X294579Y255500I-2199J107D01*
G01X289100D01*
G03X285213Y253846I-1700J-1400D01*
G02X284815Y253400I-397J-46D01*
G01X281700D01*
X280903Y254197D01*
X280902Y254278D01*
G03X278738Y256442I-2202J-38D01*
G01X278657Y256443D01*
X278600Y256500D01*
X272500D01*
X270000Y259000D01*
X257000D01*
X251000Y265000D01*
Y268994D01*
G37*
G36*
G01X278000Y151000D02*
X277500Y151500D01*
Y157500D01*
X276500Y158500D01*
Y164000D01*
X279500Y167000D01*
X289000D01*
X301000Y179000D01*
X309127D01*
G03X309273I73J1500D01*
G01X310000D01*
X312000Y181000D01*
Y182312D01*
X312010Y182342D01*
G03Y183258I-1431J458D01*
G01X312000Y183288D01*
Y186500D01*
X311000Y187500D01*
Y187625D01*
X311007Y187650D01*
G03Y188344I-1307J347D01*
G01X311000Y188369D01*
Y189500D01*
X312500Y191000D01*
X316500D01*
X318500Y193000D01*
X324000D01*
X325208Y191792D01*
X325202Y191700D01*
G03X327336Y190500I1348J-100D01*
G01X330000D01*
X332000Y188500D01*
X333500D01*
X334500Y187500D01*
X340500D01*
X341500Y188500D01*
X344016D01*
G02X344385Y187945I0J-400D01*
G03X344836Y186327I1246J-525D01*
G02X344806Y185660I-235J-324D01*
G03X346295Y185593I694J-1160D01*
G02X346325Y186260I235J324D01*
G03X346877Y187945I-694J1160D01*
G02X347246Y188500I369J155D01*
G01X348476D01*
X348516Y188480D01*
G03X349684I584J1220D01*
G01X349724Y188500D01*
X350000D01*
X352000Y186500D01*
Y186289D01*
X351999Y186277D01*
G03Y185971I1343J-153D01*
G01X352000Y185959D01*
Y183358D01*
X351994Y183333D01*
G03Y182653I1308J-340D01*
G01X352000Y182628D01*
Y182000D01*
X352500Y181500D01*
X354000D01*
X356500Y179000D01*
Y174500D01*
X356000Y174000D01*
X354000D01*
X352500Y175500D01*
X352463D01*
X352286Y175676D01*
X347200D01*
G03X346567Y175522I0J-1376D01*
G01X346524Y175500D01*
X335500D01*
X335312Y175312D01*
X335191Y175360D01*
G03X333440Y173609I-491J-1260D01*
G01X333488Y173488D01*
X333052Y173052D01*
X331647D01*
G02X331277Y173604I0J400D01*
G03X329113Y175115I-1250J515D01*
G02X328559Y175127I-271J294D01*
G03X328294Y175334I-958J-954D01*
G02X328318Y176035I205J344D01*
G03X327014Y176081I-610J1206D01*
G02X326990Y175380I-205J-344D01*
G03X326368Y173616I610J-1207D01*
G02X326004Y173052I-364J-164D01*
G01X325451D01*
X323399Y171000D01*
X312000D01*
X305500Y164500D01*
Y161500D01*
X295000Y151000D01*
X278000D01*
G37*
G36*
G01X357500Y101000D02*
X356500Y102000D01*
Y105500D01*
X363500Y112500D01*
Y129500D01*
X366500Y132500D01*
X368000D01*
X368136Y132636D01*
X368201Y132646D01*
G03X369328Y133773I-209J1336D01*
G01X369338Y133838D01*
X371042Y135542D01*
X371129Y135539D01*
G03X372527Y136937I47J1351D01*
G01X372524Y137024D01*
X373000Y137500D01*
Y140000D01*
X374000Y141000D01*
X378000D01*
X382262Y136738D01*
X382277Y136691D01*
G03X383162Y135806I1290J405D01*
G01X383209Y135791D01*
X384500Y134500D01*
Y129033D01*
X384487Y128999D01*
G03Y128035I1263J-482D01*
G01X384500Y128001D01*
Y126501D01*
G03Y124637I979J-932D01*
G01Y123416D01*
G03Y121648I1023J-884D01*
G01Y120110D01*
X384483Y120072D01*
G03Y118984I1238J-544D01*
G01X384500Y118946D01*
Y117286D01*
G03Y115714I1100J-786D01*
G01Y114294D01*
G03Y111980I700J-1157D01*
G01Y109000D01*
X384118Y108618D01*
X383934Y108803D01*
X383922Y108862D01*
G03X381253Y108446I-1326J-262D01*
G02X380855Y108000I-397J-46D01*
G01X379500D01*
X379212Y107712D01*
X379162Y107698D01*
G03X378224Y106760I364J-1302D01*
G01X378210Y106710D01*
X372500Y101000D01*
X357500D01*
G37*
G36*
G01X380000Y145000D02*
X379000Y146000D01*
Y147594D01*
X379178Y147771D01*
Y149688D01*
G03X379019Y150406I-1701J0D01*
G01X379000Y150446D01*
Y150500D01*
X378933Y150567D01*
X378921Y150586D01*
G03X376393Y151000I-1445J-898D01*
G01X373500D01*
X372414Y152086D01*
Y153093D01*
X368244Y157263D01*
G02X368395Y157923I283J283D01*
G03X368703Y160323I-445J1277D01*
G02X368737Y161008I223J332D01*
G03X369305Y161588I-637J1192D01*
G02X370003Y161615I357J-181D01*
G03X369952Y162932I1154J704D01*
G02X369254Y162905I-357J181D01*
G03X368730Y163396I-1153J-706D01*
G02Y164104I187J354D01*
G03X367470I-630J1196D01*
G02Y163396I-187J-354D01*
G03X367133Y163145I629J-1197D01*
G02X366564Y163142I-286J280D01*
G01X365600Y164107D01*
G02X365594Y164384I141J142D01*
G03X365300Y166457I-994J916D01*
G01Y169500D01*
X364952Y169848D01*
Y170287D01*
X365080Y170336D01*
G03X363693Y172603I-480J1264D01*
G01X363552Y172475D01*
X362502Y173526D01*
G02X362491Y174081I282J283D01*
G03X362200Y176157I-991J919D01*
G01Y177590D01*
G03Y179410I-1000J910D01*
G01Y180407D01*
G03Y182411I-908J1002D01*
G01Y183491D01*
G03Y185509I-900J1009D01*
G01Y186510D01*
G03Y188690I-800J1090D01*
G01Y189731D01*
G03Y191669I-943J969D01*
G01Y192555D01*
G03X362307Y194376I-943J969D01*
G02X362321Y194643I155J126D01*
G01X364978Y197301D01*
Y206853D01*
G02X365349Y207252I400J0D01*
G03Y209948I-99J1348D01*
G02X364978Y210347I29J399D01*
G01Y222478D01*
X371500Y229000D01*
Y236279D01*
G03Y238121I-2000J921D01*
G01Y239679D01*
G03Y241521I-2000J921D01*
G01Y243079D01*
G03X371669Y243617I-1999J924D01*
G01X371679Y243679D01*
X372500Y244500D01*
X382500D01*
X390797Y236203D01*
X390799Y236125D01*
G03X392925Y233999I2201J75D01*
G01X393003Y233997D01*
X398000Y229000D01*
Y213222D01*
G02X397317Y212940I-400J0D01*
G01X397009Y213247D01*
X397029Y213351D01*
G03X395949Y212271I-1329J249D01*
G01X396053Y212291D01*
X397420Y210924D01*
X398000D01*
Y209500D01*
X387000Y198500D01*
Y178500D01*
X388500Y177000D01*
Y173500D01*
X387500Y172500D01*
X384512D01*
G03X382480Y170828I-819J-1076D01*
G01X382500Y170786D01*
Y170300D01*
X382749Y170051D01*
G02X382713Y169453I-283J-283D01*
G03X382396Y169098I834J-1064D01*
G02X381700Y169123I-341J209D01*
G03X381652Y167792I-1200J-623D01*
G02X382348Y167767I341J-209D01*
G03X384611Y167555I1200J623D01*
G02X385209Y167591I315J-247D01*
G01X385913Y166887D01*
G02X385897Y166306I-283J-283D01*
G03X385620Y165961I902J-1008D01*
G02X384931Y165946I-349J195D01*
G03X383076Y164082I-1150J-711D01*
G02X383057Y163388I-209J-342D01*
G03X384878Y161536I643J-1189D01*
G02X385580Y161526I348J-197D01*
G03X387233Y160882I1197J629D01*
G01X387265Y160894D01*
X387500D01*
Y160266D01*
X387265D01*
X387233Y160278D01*
G03Y157732I-456J-1273D01*
G01X387265Y157744D01*
X387500D01*
Y157173D01*
X387281D01*
X387261Y157176D01*
G03X387077Y154500I-262J-1326D01*
G02X387500Y154101I23J-399D01*
G01Y151374D01*
G02X387044Y150978I-400J0D01*
G03X386174Y148471I-191J-1338D01*
G02X386255Y147842I-201J-346D01*
G01X384144Y145731D01*
Y145644D01*
X383500Y145000D01*
X380000D01*
G37*
G36*
G01X396068Y145500D02*
X395500Y146068D01*
Y147000D01*
X395306Y147194D01*
Y147307D01*
X394075Y148538D01*
X393963D01*
X393500Y149000D01*
X392568D01*
X391566Y150002D01*
Y154555D01*
G02X392249Y154837I400J0D01*
G03X394342Y155054I959J953D01*
G02X395014I336J-217D01*
G03Y156526I1134J736D01*
G02X394342I-336J217D01*
G03X392249Y156743I-1134J-736D01*
G02X391566Y157025I-283J282D01*
G01Y162000D01*
X392566Y163000D01*
X403500D01*
X404500Y162000D01*
X404822D01*
G03X407178I1178J663D01*
G01X407623D01*
X407678Y161885D01*
G03X410122I1222J578D01*
G01X410177Y162000D01*
X410643D01*
G03X412957I1157J700D01*
G01X413588D01*
G03X416012I1212J600D01*
G01X416585D01*
G03X418985I1200J622D01*
G01X419623D01*
G03X419946Y161615I1179J661D01*
G02X419967Y161016I-254J-309D01*
G03X421758Y161081I932J-979D01*
G02X421737Y161680I254J309D01*
G03X421985Y162000I-933J979D01*
G01X428000D01*
X429000Y163000D01*
X433757D01*
G03X435712Y162788I1078J817D01*
G01X437000Y161500D01*
Y160000D01*
X435000Y158000D01*
X432000D01*
X431500Y157500D01*
X420500D01*
X419500Y156500D01*
X414000D01*
X413706Y156206D01*
X413600Y156229D01*
G03X411995Y154611I-286J-1321D01*
G01X412000Y154589D01*
Y152000D01*
X411000Y151000D01*
X409479D01*
X409437Y151021D01*
G03X408237I-600J-1212D01*
G01X408195Y151000D01*
X407500D01*
X404000Y147500D01*
Y146500D01*
X403500Y146000D01*
X402000D01*
X401500Y145500D01*
X396068D01*
G37*
G36*
G01X670630Y32013D02*
G02X670768Y31446I-197J-348D01*
G03X671813Y29358I1132J-739D01*
G02X672000Y29158I-13J-200D01*
G01Y20500D01*
X670500Y19000D01*
Y15917D01*
G03Y14097I1000J-910D01*
G01Y13554D01*
G03X670104Y11808I790J-1097D01*
G01X670176Y11676D01*
X668000Y9500D01*
X617500D01*
X616688Y10312D01*
G02X616886Y10986I283J283D01*
G03X615279Y12593I-286J1321D01*
G02X614605Y12395I-391J85D01*
G01X613500Y13500D01*
Y29417D01*
G02X614175Y29707I400J-1D01*
G03Y31673I928J983D01*
G02X613500Y31963I-275J291D01*
G01Y37500D01*
X617000Y41000D01*
Y49500D01*
X619000Y51500D01*
X657500D01*
X669500Y39500D01*
Y34000D01*
X669980Y33520D01*
X669962Y33418D01*
G03X670630Y32013I1333J-228D01*
G37*
G36*
G01X761750Y5750D02*
X752000Y15500D01*
Y46407D01*
G02X752415Y46807I400J0D01*
G03Y51207I85J2200D01*
G02X752000Y51607I-15J400D01*
G01Y70500D01*
X730433Y92067D01*
G02X730637Y92742I283J283D01*
G03X729048Y96776I-436J2158D01*
G02X728525Y96869I-209J341D01*
G03X726038Y97566I-1725J-1369D01*
G02X725500Y97941I-138J375D01*
G01Y106623D01*
G03Y110177I-1300J1777D01*
G01Y126802D01*
G02X726138Y127123I400J0D01*
G03X729211Y130212I1310J1770D01*
G02X729434Y130840I320J240D01*
G03X729880Y134948I-534J2136D01*
G02X729711Y135505I178J358D01*
G03X729161Y138331I-1911J1095D01*
G02X729067Y138854I247J314D01*
G03X726098Y141914I-1880J1146D01*
G02X725500Y142261I-198J347D01*
G01Y174117D01*
G03X726114Y174642I-1100J1908D01*
G02X726636Y174731I311J-251D01*
G03X729065Y178402I1164J1869D01*
G02X729012Y179012I230J327D01*
G01X736244Y186244D01*
X736358Y186209D01*
G03X739106Y188957I642J2106D01*
G01X739071Y189071D01*
X743307Y193307D01*
X743375Y193315D01*
G03X745285Y195225I-275J2185D01*
G01X745293Y195293D01*
X768000Y218000D01*
Y231707D01*
G02X768547Y232079I400J0D01*
G03Y236921I953J2421D01*
G02X768000Y237293I-147J372D01*
G01Y249869D01*
G02X768533Y250247I400J1D01*
G03Y255153I867J2453D01*
G02X768000Y255531I-133J377D01*
G01Y267000D01*
X770500Y269500D01*
X794500D01*
X800000Y264000D01*
Y213500D01*
X823500Y190000D01*
Y14500D01*
X814750Y5750D01*
X787864D01*
G02X787549Y6396I0J400D01*
G03X783451I-2049J1604D01*
G02X783136Y5750I-315J-246D01*
G01X761750D01*
G37*
G36*
G01X813000Y203000D02*
X802000Y214000D01*
Y265000D01*
X796000Y271000D01*
X769000D01*
X768000Y272000D01*
Y284000D01*
X771500Y287500D01*
X822500D01*
X823500Y286500D01*
Y204500D01*
X822000Y203000D01*
X813000D01*
G37*
%LPC*%
G75*
G36*
G01X54153Y132402D02*
G03X54685Y132387I274J291D01*
G02X54590Y129098I1415J-1687D01*
G03X54058Y129113I-274J-291D01*
G02X54153Y132402I-1415J1687D01*
G37*
G36*
G01X67273Y125938D02*
G03X67119Y125292I140J-375D01*
G02X64727Y125862I-1619J-1492D01*
G03X64881Y126508I-140J375D01*
G02X67273Y125938I1619J1492D01*
G37*
G36*
G01X105770Y109093D02*
G03Y108507I273J-293D01*
G02X102230I-1770J-1907D01*
G03Y109093I-273J293D01*
G02X102277Y112950I1770J1907D01*
G03Y113550I-264J300D01*
G02X105723I1723J1950D01*
G03Y112950I264J-300D01*
G02X105770Y109093I-1723J-1950D01*
G37*
G36*
G01X40147Y102538D02*
G03X40181Y103139I-246J315D01*
G02X40050Y103277I1821J1859D01*
G03X39450I-300J-264D01*
G02X35550I-1950J1723D01*
G03X34950I-300J-264D01*
G02Y106723I-1950J1723D01*
G03X35550I300J264D01*
G02X39450I1950J-1723D01*
G03X40050I300J264D01*
G02X43331Y102764I1950J-1723D01*
G03X43223Y102171I205J-344D01*
G02X40147Y102538I-1723J-1371D01*
G37*
G36*
G01X69756Y93342D02*
G03Y93058I141J-142D01*
G02X66644I-1556J-1558D01*
G03Y93342I-141J142D01*
G02X69756I1556J1558D01*
G37*
G36*
G01X91891Y86610D02*
G03X92153Y86103I380J-125D01*
G02X89409Y84690I-653J-2103D01*
G03X89147Y85197I-380J125D01*
G02X88341Y88949I653J2103D01*
G03X88372Y89518I-265J300D01*
G02X91459Y89351I1628J1482D01*
G03X91428Y88782I265J-300D01*
G02X91891Y86610I-1628J-1482D01*
G37*
G36*
G01X11372Y148030D02*
G03X11385Y148643I-250J312D01*
G02X14728Y148570I1715J1957D01*
G03X14715Y147957I250J-312D01*
G02X14723Y144050I-1715J-1957D01*
G03Y143450I264J-300D01*
G02Y139550I-1723J-1950D01*
G03Y138950I264J-300D01*
G02X11277I-1723J-1950D01*
G03Y139550I-264J300D01*
G02Y143450I1723J1950D01*
G03Y144050I-264J300D01*
G02X11372Y148030I1723J1950D01*
G37*
G36*
G01X9112Y264493D02*
Y260628D01*
X9102Y260544D01*
G02X6088Y260713I-1502J169D01*
G01Y264483D01*
G02X9112Y264493I1512J0D01*
G37*
G36*
G01X15102Y258531D02*
Y254666D01*
X15092Y254582D01*
G02X12078Y254751I-1502J169D01*
G01Y258521D01*
G02X15102Y258531I1512J0D01*
G37*
G36*
G01X9112Y252682D02*
Y248817D01*
X9102Y248733D01*
G02X6088Y248902I-1502J169D01*
G01Y252673D01*
G02X9112Y252682I1512J-1D01*
G37*
G36*
G01X15102Y246720D02*
Y242855D01*
X15092Y242771D01*
G02X12078Y242940I-1502J169D01*
G01Y246710D01*
G02X15102Y246720I1512J0D01*
G37*
G36*
G01X9112Y240871D02*
Y237006D01*
X9102Y236922D01*
G02X6088Y237091I-1502J169D01*
G01Y240861D01*
G02X9112Y240871I1512J0D01*
G37*
G36*
G01X14602Y234909D02*
Y231044D01*
X14592Y230960D01*
G02X11578Y231129I-1502J169D01*
G01Y234900D01*
G02X14602Y234909I1512J-1D01*
G37*
G36*
G01X36302Y212164D02*
Y208336D01*
G02X33298I-1502J-36D01*
G01Y212164D01*
G02X36302I1502J36D01*
G37*
G36*
G01X71410Y246899D02*
G03X71677Y246799I183J81D01*
G02X73008Y246964I924J-1999D01*
G03X73469Y247256I74J393D01*
G02X77067Y248342I2131J-556D01*
G03X77350Y248359I133J149D01*
G02X80695Y248306I1650J-1459D01*
G03X80978Y248281I154J128D01*
G02X80705Y245194I1422J-1681D01*
G03X80422Y245219I-154J-128D01*
G02X77533Y245258I-1422J1681D01*
G03X77250Y245241I-133J-149D01*
G02X75192Y244536I-1650J1459D01*
G03X74731Y244244I-74J-393D01*
G02X70590Y243901I-2131J556D01*
G03X70323Y244001I-183J-81D01*
G02X71410Y246899I-923J1999D01*
G37*
G36*
G01X85342Y189444D02*
G03X85058I-142J-141D01*
G02Y192556I-1558J1556D01*
G03X85342I142J141D01*
G02Y189444I1558J-1556D01*
G37*
G36*
G01X92951Y214476D02*
G02X92387Y216539I-2139J524D01*
G03X93061Y216724I286J280D01*
G02X93625Y214661I2139J-524D01*
G03X92951Y214476I-286J-280D01*
G37*
G36*
G01X55798Y245298D02*
G03X56010Y245785I-168J363D01*
G02X56069Y247316I2092J686D01*
G03X55960Y247577I-185J76D01*
G02X56079Y251694I840J2036D01*
G03X56233Y252353I-130J378D01*
G02X58521Y251819I1567J1547D01*
G03X58367Y251160I130J-378D01*
G02X58833Y248768I-1567J-1547D01*
G03X58942Y248507I185J-76D01*
G02X59028Y244473I-840J-2036D01*
G03X58816Y243986I168J-363D01*
G02X55798Y245298I-2092J-686D01*
G37*
G36*
G01X55832Y221459D02*
G03X55850Y221742I-132J150D01*
G02X55992Y224804I1650J1458D01*
G03X56000Y225087I-137J145D01*
G02X55729Y227762I1600J1513D01*
G03X55638Y228286I-340J211D01*
G02X58880Y228847I1371J1723D01*
G03X58971Y228323I340J-211D01*
G02X59108Y224996I-1371J-1723D01*
G03X59100Y224713I137J-145D01*
G02X58955Y221547I-1600J-1513D01*
G03X58937Y221264I132J-150D01*
G02X55832Y221459I-1650J-1458D01*
G37*
G36*
G01X55860Y212274D02*
G03X55891Y212812I-280J286D01*
G02X59140Y212626I1709J1388D01*
G03X59109Y212088I280J-286D01*
G02X55860Y212274I-1709J-1388D01*
G37*
G36*
G01X259653Y267108D02*
G03X260114Y266798I391J84D01*
G02X258347Y264167I386J-2168D01*
G03X257886Y264477I-391J-84D01*
G02X259653Y267108I-386J2168D01*
G37*
G36*
G01X343243Y184740D02*
G03X343232Y184220I298J-266D01*
G02X341178Y184260I-1044J-859D01*
G03X341189Y184780I-298J266D01*
G02X343243Y184740I1044J859D01*
G37*
G36*
G01X331643Y179854D02*
G03X331137I-253J-309D01*
G02Y181946I-857J1046D01*
G03X331643I253J309D01*
G02Y179854I857J-1046D01*
G37*
G36*
G01X305114Y171994D02*
G03X304794Y172416I-399J30D01*
G02X304096Y172763I297J1472D01*
G03X303570Y172767I-265J-299D01*
G02X303586Y175031I-979J1139D01*
G03X304112Y175027I265J299D01*
G02X306589Y173776I979J-1139D01*
G03X306909Y173354I399J-30D01*
G02X307564Y173044I-296J-1472D01*
G03X308090Y173060I254J309D01*
G02X308160Y170798I1022J-1100D01*
G03X307634Y170782I-254J-309D01*
G02X305114Y171994I-1022J1100D01*
G37*
G36*
G01X324120Y181265D02*
G02X322588Y181061I-620J-1202D01*
G03X322501Y181711I-270J295D01*
G02X324033Y181915I620J1202D01*
G03X324120Y181265I270J-295D01*
G37*
G36*
G01X382528Y118916D02*
G03X382516Y118346I274J-291D01*
G02X380622Y118384I-966J-946D01*
G03X380634Y118954I-274J291D01*
G02X382528Y118916I966J946D01*
G37*
G36*
G01X362865Y104684D02*
G03X362485Y104242I18J-400D01*
G02X361079Y105450I-1344J-143D01*
G03X361459Y105892I-18J400D01*
G02X362865Y104684I1344J143D01*
G37*
G36*
G01X378374Y122240D02*
G02X377119Y122276I-662J-1179D01*
G03X377139Y122984I-176J359D01*
G02X378394Y122948I662J1179D01*
G03X378374Y122240I176J-359D01*
G37*
G36*
G01X370781Y114808D02*
G02X369215Y114809I-784J-1102D01*
G03X369216Y115461I-231J326D01*
G02X369341Y117744I784J1102D01*
G03X369364Y118429I-194J349D01*
G02Y120697I736J1134D01*
G03X369341Y121382I-217J336D01*
G02X368978Y121678I660J1180D01*
G03X368366Y121670I-303J-261D01*
G02X366525Y123621I-1045J858D01*
G03X366502Y124283I-236J323D01*
G02X368314Y126224I719J1145D01*
G03X368976Y126247I323J236D01*
G02X371131Y126427I1145J-719D01*
G03X371747Y126450I299J266D01*
G02X371811Y124729I1074J-822D01*
G03X371195Y124706I-299J-266D01*
G02X370793Y124355I-1073J823D01*
G03X370765Y123678I198J-347D01*
G02X370736Y121429I-765J-1115D01*
G03X370759Y120744I217J-336D01*
G02X371068Y120506I-662J-1179D01*
G03X371662Y120529I287J279D01*
G02X371732Y118720I1038J-866D01*
G03X371138Y118697I-287J-279D01*
G02X370759Y118382I-1039J865D01*
G03X370736Y117697I194J-349D01*
G02X370782Y115460I-736J-1134D01*
G03X370781Y114808I231J-326D01*
G37*
G36*
G01X378539Y113195D02*
G02X377074Y113204I-739J-1132D01*
G03X377079Y113876I-214J338D01*
G02X378544Y113867I739J1132D01*
G03X378539Y113195I214J-338D01*
G37*
G36*
G01X377162Y212658D02*
G03Y212042I255J-308D01*
G02X375438I-862J-1042D01*
G03Y212658I-255J308D01*
G02X375353Y214665I862J1042D01*
G03Y215235I-281J285D01*
G02X377247I947J965D01*
G03Y214665I281J-285D01*
G02X377162Y212658I-947J-965D01*
G37*
G36*
G01X385675Y207491D02*
G03X385637Y206912I256J-308D01*
G02X383779Y207033I-993J-918D01*
G03X383817Y207612I-256J308D01*
G02X385675Y207491I993J918D01*
G37*
G36*
G01X365617Y187672D02*
G03X365573Y187077I244J-317D01*
G02X363775Y187209I-973J-939D01*
G03X363819Y187804I-244J317D01*
G02X363884Y189745I973J939D01*
G03X363898Y190028I-134J148D01*
G02X363964Y191922I997J913D01*
G03X363971Y192205I-137J145D01*
G02X365878Y192160I976J936D01*
G03X365871Y191877I137J-145D01*
G02X365803Y189939I-976J-936D01*
G03X365789Y189656I134J-148D01*
G02X365617Y187672I-997J-913D01*
G37*
G36*
G01X373536Y180424D02*
G03X373490Y179899I277J-289D01*
G02X371464Y180076I-1091J-799D01*
G03X371510Y180601I-277J289D01*
G02X373536Y180424I1091J799D01*
G37*
G36*
G01X365623Y176211D02*
G03X365622Y175686I301J-263D01*
G02X363584Y175692I-1022J-886D01*
G03X363585Y176217I-301J263D01*
G02X365623Y176211I1022J886D01*
G37*
G36*
G01X389939Y228532D02*
G02X388422Y228506I-739J-1132D01*
G03X388411Y229168I-230J327D01*
G02X389928Y229194I739J1132D01*
G03X389939Y228532I230J-327D01*
G37*
G36*
G01X383417Y227146D02*
G02X382021Y227169I-717J-1146D01*
G03X382033Y227854I-201J346D01*
G02X383429Y227831I717J1146D01*
G03X383417Y227146I201J-346D01*
G37*
G36*
G01X380429Y214669D02*
G02X379033Y214646I-679J-1169D01*
G03X379021Y215331I-213J339D01*
G02X378838Y217542I679J1169D01*
G03Y218158I-255J308D01*
G02X380562I862J1042D01*
G03Y217542I255J-308D01*
G02X380417Y215354I-862J-1042D01*
G03X380429Y214669I213J-339D01*
G37*
G36*
G01X370321Y196942D02*
G02X370082Y195419I978J-934D01*
G03X369433Y195521I-360J-174D01*
G02X369672Y197044I-978J934D01*
G03X370321Y196942I360J174D01*
G37*
G36*
G01X382777Y195306D02*
G02X382404Y196578I-1317J304D01*
G03X383073Y196774I279J286D01*
G02X383446Y195502I1317J-304D01*
G03X382777Y195306I-279J-286D01*
G37*
G36*
G01X374805Y191436D02*
G02X373134Y191389I-806J-1086D01*
G03X373117Y192017I-256J307D01*
G02X374929Y194005I805J1086D01*
G03X375586Y194096I298J267D01*
G02X376210Y194716I1213J-597D01*
G03X376233Y195424I-175J360D01*
G02X377490Y195384I667J1176D01*
G03X377467Y194676I175J-360D01*
G02X375793Y192598I-667J-1176D01*
G03X375136Y192507I-298J-267D01*
G02X374788Y192064I-1214J596D01*
G03X374805Y191436I256J-307D01*
G37*
G36*
G01X369831Y187264D02*
G02X368334Y187363I-823J-1073D01*
G03X368378Y188027I-199J347D01*
G02X368354Y190154I822J1073D01*
G03X368332Y190794I-251J312D01*
G02X369952Y190849I773J1109D01*
G03X369974Y190209I251J-312D01*
G02X369875Y187928I-774J-1109D01*
G03X369831Y187264I199J-347D01*
G37*
G36*
G01X381588Y178224D02*
G02X380403Y178715I-1048J-854D01*
G03X380672Y179366I-41J398D01*
G02X381107Y181425I1048J854D01*
G03X381125Y182128I-181J356D01*
G02X380502Y183680I675J1172D01*
G03X380208Y184182I-384J112D01*
G02X379851Y186680I302J1318D01*
G03X379994Y187242I-196J349D01*
G02X381799Y186780I1145J718D01*
G03X381656Y186218I196J-349D01*
G02X381808Y185120I-1146J-718D01*
G03X382102Y184618I384J-112D01*
G02X382935Y184034I-303J-1318D01*
G03X383586Y184004I336J217D01*
G02X383890Y184288I1064J-834D01*
G03X383878Y184957I-225J331D01*
G02X383836Y187215I722J1143D01*
G03X383860Y187857I-226J330D01*
G02X384027Y190078I848J1053D01*
G03X384021Y190772I-202J345D01*
G02X385365Y190782I663J1178D01*
G03X385371Y190088I202J-345D01*
G02X385472Y187795I-663J-1178D01*
G03X385448Y187153I226J-330D01*
G02X385360Y184982I-848J-1053D01*
G03X385372Y184313I225J-331D01*
G02X385321Y181996I-722J-1143D01*
G03X385342Y181291I199J-347D01*
G02X383543Y179451I-602J-1211D01*
G03X382854Y179483I-354J-186D01*
G02X381857Y178875I-1133J737D01*
G03X381588Y178224I41J-398D01*
G37*
G36*
G01X377542Y176789D02*
G02X376095Y176775I-712J-1149D01*
G03X376088Y177451I-217J336D01*
G02X376033Y179713I712J1149D01*
G03X376020Y180381I-227J330D01*
G02X377509Y180411I722J1143D01*
G03X377522Y179743I227J-330D01*
G02X377535Y177465I-722J-1143D01*
G03X377542Y176789I217J-336D01*
G37*
G36*
G01X368687Y169664D02*
G02X367240Y169618I-687J-1164D01*
G03X367219Y170294I-224J331D01*
G02X369005Y172245I687J1164D01*
G03X369689Y172300I325J233D01*
G02X371670Y170589I1211J-600D01*
G03X371716Y169904I228J-329D01*
G02X370330Y169811I-615J-1204D01*
G03X370284Y170496I-228J329D01*
G02X369801Y170913I617J1203D01*
G03X369117Y170858I-325J-233D01*
G02X368666Y170340I-1212J600D01*
G03X368687Y169664I224J-331D01*
G37*
G36*
G01X378618Y164480D02*
G02Y166000I-1118J760D01*
G03X379280I331J225D01*
G02Y164480I1118J-760D01*
G03X378618I-331J-225D01*
G37*
G36*
G01X372357Y158282D02*
G02X372251Y159760I-1181J658D01*
G03X372919Y159808I318J242D01*
G02X373025Y158330I1181J-658D01*
G03X372357Y158282I-318J-242D01*
G37*
G36*
G01X663201Y13975D02*
G03X663240Y13405I299J-266D01*
G02X661350Y13278I-880J-1026D01*
G03X661311Y13848I-299J266D01*
G02X663201Y13975I880J1026D01*
G37*
G36*
G01X667005Y13740D02*
G03X666943Y13169I246J-316D01*
G02X665071Y13374I-1042J-862D01*
G03X665133Y13945I-246J316D01*
G02X667005Y13740I1042J862D01*
G37*
G36*
G01X663624Y31153D02*
G02X663440Y29763I1054J-847D01*
G03X662762Y29853I-366J-161D01*
G02X661164Y31937I-1054J846D01*
G03X661345Y32509I-162J366D01*
G02X663047Y31969I1158J698D01*
G03X662866Y31397I162J-366D01*
G02X662946Y31243I-1157J-699D01*
G03X663624Y31153I366J161D01*
G37*
G36*
G01X648326Y29343D02*
G02X645715Y29188I-1326J264D01*
G03X645053Y29348I-380J-124D01*
G02X643259Y31366I-952J960D01*
G03X643168Y32047I-248J313D01*
G02X644541Y32231I532J1243D01*
G03X644632Y31550I248J-313D01*
G02X645385Y30726I-532J-1243D01*
G03X646047Y30566I380J124D01*
G02X647642Y30797I953J-959D01*
G03X648224Y31071I190J352D01*
G02X648908Y29617I1326J-264D01*
G03X648326Y29343I-190J-352D01*
G37*
G36*
G01X649444Y13896D02*
G02X647847Y13666I-644J-1189D01*
G03X647756Y14301I-282J284D01*
G02X647200Y14866I644J1189D01*
G03X646493Y14870I-355J-184D01*
G02X645608Y14191I-1192J638D01*
G03X645356Y13597I92J-389D01*
G02X643885Y14223I-1162J-690D01*
G03X644137Y14817I-92J389D01*
G02X646500Y16131I1163J690D01*
G03X647207Y16127I355J184D01*
G02X649353Y14531I1193J-637D01*
G03X649444Y13896I282J-284D01*
G37*
G36*
G01X812359Y194680D02*
G03Y194120I286J-280D01*
G02X808641I-1859J-1820D01*
G03Y194680I-286J280D01*
G02X812359I1859J1820D01*
G37*
G36*
G01X765557Y190725D02*
G03Y190085I240J-320D01*
G02X762443I-1557J-2085D01*
G03Y190725I-240J320D01*
G02X762375Y194843I1557J2085D01*
G03Y195467I-249J312D01*
G02X762443Y199585I1625J2033D01*
G03Y200225I-240J320D01*
G02X765557I1557J2085D01*
G03Y199585I240J-320D01*
G02X765625Y195467I-1557J-2085D01*
G03Y194843I249J-312D01*
G02X765557Y190725I-1625J-2033D01*
G37*
G36*
G01X789242Y181833D02*
G03X789259Y181550I149J-133D01*
G02X786158Y181367I-1459J-1650D01*
G03X786141Y181650I-149J133D01*
G02X785762Y184512I1459J1649D01*
G01X785852Y184648D01*
X782500Y188000D01*
Y204000D01*
X786000Y207500D01*
Y220000D01*
X788000Y222000D01*
X791000D01*
X792500Y220500D01*
Y208500D01*
X793000Y208000D01*
X795000D01*
X796500Y206500D01*
Y203000D01*
X796000Y202500D01*
Y195000D01*
X801500Y189500D01*
Y186000D01*
X800000Y184500D01*
X790076D01*
G03X789695Y183977I0J-400D01*
G02X789242Y181833I-2095J-677D01*
G37*
G36*
G01X731750Y160842D02*
G03X731150I-300J-265D01*
G02Y163758I-1650J1458D01*
G03X731750I300J265D01*
G02X734881Y163930I1650J-1458D01*
G03X735419I269J296D01*
G02Y160670I1481J-1630D01*
G03X734881I-269J-296D01*
G02X731750Y160842I-1481J1630D01*
G37*
G36*
G01X749019Y160370D02*
G03X748481I-269J-296D01*
G02Y163630I-1481J1630D01*
G03X749019I269J296D01*
G02Y160370I1481J-1630D01*
G37*
G36*
G01X811273Y158919D02*
G03X811258Y158386I291J-275D01*
G02X807827Y158481I-1758J-1486D01*
G03X807842Y159014I-291J275D01*
G02X808007Y162162I1758J1486D01*
G03X808022Y162724I-277J289D01*
G02X811293Y162638I1678J1576D01*
G03X811278Y162076I277J-289D01*
G02X811273Y158919I-1678J-1576D01*
G37*
G36*
G01X786822Y142651D02*
G03X786208I-307J-255D01*
G02Y145469I-1693J1409D01*
G03X786822I307J255D01*
G02X790208I1693J-1409D01*
G03X790822I307J255D01*
G02X791106Y145753I1693J-1409D01*
G03Y146367I-255J307D01*
G02X794208Y149469I1409J1693D01*
G03X794822I307J255D01*
G02X798208I1693J-1409D01*
G03X798822I307J255D01*
G02X801924Y146367I1693J-1409D01*
G03Y145753I255J-307D01*
G02X798822Y142651I-1409J-1693D01*
G03X798208I-307J-255D01*
G02X794822I-1693J1409D01*
G03X794208I-307J-255D01*
G02X790822I-1693J1409D01*
G03X790208I-307J-255D01*
G02X786822I-1693J1409D01*
G37*
G36*
G01X759934Y133699D02*
G03X760123Y133080I320J-241D01*
G02X757642Y132325I-722J-2080D01*
G03X757453Y132944I-320J241D01*
G02X759934Y133699I722J2080D01*
G37*
G36*
G01X812548Y132296D02*
G03Y131704I269J-296D01*
G02X809452I-1548J-1704D01*
G03Y132296I-269J296D01*
G02Y135704I1548J1704D01*
G03Y136296I-269J296D01*
G02X809373Y139629I1548J1704D01*
G03X809403Y140162I-282J283D01*
G02X812827Y139971I1798J1438D01*
G03X812797Y139438I282J-283D01*
G02X812548Y136296I-1797J-1438D01*
G03Y135704I269J-296D01*
G02Y132296I-1548J-1704D01*
G37*
G36*
G01X746513Y132070D02*
G03Y131456I255J-307D01*
G02X743695I-1409J-1693D01*
G03Y132070I-255J307D01*
G02X743411Y132354I1409J1693D01*
G03X742797I-307J-255D01*
G02Y135172I-1693J1409D01*
G03X743411I307J255D01*
G02X743695Y135456I1693J-1409D01*
G03Y136070I-255J307D01*
G02X746513I1409J1693D01*
G03Y135456I255J-307D01*
G02X746797Y135172I-1409J-1693D01*
G03X747411I307J255D01*
G02Y132354I1693J-1409D01*
G03X746797I-307J-255D01*
G02X746513Y132070I-1693J1409D01*
G37*
G36*
G01X732000Y120498D02*
G03X731600Y120114I0J-400D01*
G02X729400Y122402I-2200J86D01*
G03X729800Y122786I0J400D01*
G02X732000Y120498I2200J-86D01*
G37*
G36*
G01X753461Y117775D02*
G03X753876Y117298I392J-78D01*
G02X751839Y115525I123J-2198D01*
G03X751424Y116002I-392J78D01*
G02X751380Y115999I-172J2195D01*
G03X750995Y115631I14J-400D01*
G02X748720Y118001I-2195J169D01*
G03X749105Y118369I-14J400D01*
G02X753461Y117775I2195J-169D01*
G37*
G36*
G01X768111Y111833D02*
G03X767650Y111525I-70J-394D01*
G02X765889Y114167I-2150J475D01*
G03X766350Y114475I70J394D01*
G02X768111Y111833I2150J-475D01*
G37*
G36*
G01X776680Y100641D02*
G03X776120I-280J-286D01*
G02X772577Y104450I-1820J1859D01*
G03Y105050I-264J300D01*
G02X776120Y108859I1723J1950D01*
G03X776680I280J286D01*
G02X780223Y105050I1820J-1859D01*
G03Y104450I264J-300D01*
G02X776680Y100641I-1723J-1950D01*
G37*
G36*
G01X801059Y100980D02*
G03Y100420I286J-280D01*
G02X797341I-1859J-1820D01*
G03Y100980I-286J280D01*
G02X797301Y104579I1859J1820D01*
G03X797275Y105152I-291J274D01*
G02X797437Y109180I1725J1948D01*
G03Y109820I-240J320D01*
G02X797141Y113720I1563J2080D01*
G03Y114280I-286J280D01*
G02X800725Y118048I1859J1820D01*
G03X801325Y118128I265J299D01*
G02X805359Y114880I2175J-1427D01*
G03Y114320I286J-280D01*
G02X801775Y110552I-1859J-1820D01*
G03X801175Y110472I-265J-299D01*
G02X800563Y109820I-2175J1428D01*
G03Y109180I240J-320D01*
G02X801254Y108401I-1562J-2081D01*
G03X801800Y108254I346J199D01*
G02X802305Y103523I1300J-2254D01*
G03X801785Y103096I-122J-381D01*
G02X801059Y100980I-2585J-296D01*
G37*
G36*
G01X785550Y91277D02*
G03X784950I-300J-264D01*
G02Y94723I-1950J1723D01*
G03X785550I300J264D01*
G02Y91277I1950J-1723D01*
G37*
G36*
G01X794550Y81277D02*
G03X793950I-300J-264D01*
G02X790381Y85037I-1950J1723D01*
G03Y85663I-249J313D01*
G02X793950Y89423I1619J2037D01*
G03X794550I300J264D01*
G02X798119Y85663I1950J-1723D01*
G03Y85037I249J-313D01*
G02X794550Y81277I-1619J-2037D01*
G37*
G36*
G01X776519Y29677D02*
G03X775981I-269J-296D01*
G02Y32937I-1481J1630D01*
G03X776519I269J296D01*
G02Y29677I1481J-1630D01*
G37*
G36*
G01X768668Y139043D02*
G02X768510Y140896I-2068J757D01*
G03X769232Y140957I347J199D01*
G02X769390Y139104I2068J-757D01*
G03X768668Y139043I-347J-199D01*
G37*
G36*
G01X741621Y115492D02*
G02X737354Y115394I-2121J-592D01*
G03X736862Y115871I-390J90D01*
G02X738446Y117506I-562J2129D01*
G03X738938Y117029I390J-90D01*
G02X739579Y117101I564J-2129D01*
G03X739979Y117608I15J400D01*
G02X742021Y115999I2121J592D01*
G03X741621Y115492I-15J-400D01*
G37*
G36*
G01X784043Y115384D02*
G02X781957I-1043J-2384D01*
G03Y116116I-161J366D01*
G02X781277Y120450I1043J2384D01*
G03Y121050I-264J300D01*
G02X784723I1723J1950D01*
G03Y120450I264J-300D01*
G02X784043Y116116I-1723J-1950D01*
G03Y115384I161J-366D01*
G37*
G36*
G01X760885Y105641D02*
G02X760617Y102542I1419J-1684D01*
G03X760335Y102566I-153J-129D01*
G02X756779Y103719I-1419J1684D01*
G03X756536Y103864I-194J-49D01*
G02X754994Y107959I-537J2136D01*
G03X755046Y108638I-183J356D01*
G02X757404Y108428I1354J1862D01*
G03X757336Y107751I175J-359D01*
G02X758137Y106531I-1336J-1750D01*
G03X758380Y106386I194J49D01*
G02X760603Y105665I536J-2136D01*
G03X760885Y105641I153J129D01*
G37*
G36*
G01X766828Y85962D02*
G02X765292Y87278I-2328J-1162D01*
G03X765772Y87838I122J381D01*
G02X767308Y86522I2328J1162D01*
G03X766828Y85962I-122J-381D01*
G37*
G36*
G01X789391Y13017D02*
G02X788201Y11112I1109J-2017D01*
G03X787609Y11483I-400J20D01*
G02X788799Y13388I-1109J2017D01*
G03X789391Y13017I400J-20D01*
G37*
G36*
G01X812558Y266484D02*
G03X812811Y265972I378J-132D01*
G02X809542Y264355I-812J-2472D01*
G03X809289Y264867I-378J132D01*
G02X809288Y269811I811J2472D01*
G03X809546Y270308I-124J380D01*
G02X809601Y271987I2489J759D01*
G03X809343Y272511I-374J141D01*
G02X810407Y277584I758J2489D01*
G03X810830Y278118I47J397D01*
G02X813295Y275209I5170J1882D01*
G03X812699Y274879I-197J-348D01*
G02X812534Y274080I-2599J120D01*
G03X812792Y273556I374J-141D01*
G02X812847Y268595I-757J-2489D01*
G03X812589Y268098I124J-380D01*
G02X812558Y266484I-2489J-759D01*
G37*
G54D32*
X37600Y203700D03*
X40400Y207800D03*
Y212700D03*
X297000Y160200D03*
G54D31*
X14500Y198000D03*
X770500Y13007D03*
X759000Y37507D03*
X760400Y88700D03*
X761300Y95700D03*
X763600Y168000D03*
X781500Y51000D03*
X777000Y93100D03*
G54D33*
X276811Y263386D03*
X296811D03*
G54D30*
X28400Y81400D03*
X41200Y90300D03*
X42000Y96000D03*
X40500Y124300D03*
X60800Y87500D03*
X62900Y79900D03*
X53500Y120400D03*
X57600Y136900D03*
X58000Y141750D03*
X69235Y99735D03*
X90500Y101000D03*
X86100Y97700D03*
X86500Y113500D03*
X80500D03*
X85500Y135400D03*
X106100Y158700D03*
X17500Y190200D03*
X16844Y203100D03*
X17301Y212401D03*
X17300Y218307D03*
X16400Y224212D03*
X21900Y205400D03*
X44861Y227261D03*
X80563Y214700D03*
X88900Y246700D03*
X100600Y221100D03*
X110166Y239500D03*
X112700Y231400D03*
X155300Y254000D03*
X165700D03*
X195000Y234000D03*
X206000D03*
X227000Y275500D03*
X285000Y261700D03*
X304300Y262900D03*
X326100Y267000D03*
X322000Y264300D03*
X738500Y90000D03*
X736900Y98500D03*
X749500Y101500D03*
X757900Y124700D03*
X752191Y146613D03*
X746000Y182300D03*
X769800Y133000D03*
X779000Y142000D03*
X793000Y174500D03*
X805500Y128000D03*
G54D34*
X326408Y182292D03*
X336915Y177423D03*
X337863Y180545D03*
X330821Y177402D03*
X329313Y188000D03*
X366400Y112200D03*
X365721Y115528D03*
X368721Y108528D03*
X365316Y108130D03*
X367121Y128628D03*
X381900Y113000D03*
X380443Y130102D03*
X381500Y123200D03*
X380400Y133928D03*
X381600Y126427D03*
X369021Y180128D03*
X369450Y212040D03*
X371100Y199500D03*
X372700Y213700D03*
X369580Y215400D03*
X372800Y221600D03*
X369580Y218800D03*
X383500Y159000D03*
X380500Y162025D03*
X377500Y156000D03*
X374300Y155800D03*
X380477Y171605D03*
X386600Y174900D03*
X381280Y191550D03*
X382471Y199843D03*
X385900Y222600D03*
X372950Y217400D03*
X385900Y218400D03*
X382600Y222600D03*
X385947Y226500D03*
X392100Y213700D03*
X392000Y217200D03*
X395700Y220600D03*
X395600Y224400D03*
X391950Y220800D03*
X395700Y217000D03*
X389100Y224000D03*
X410100Y157700D03*
X430542Y160753D03*
X426900Y160040D03*
X615907Y24856D03*
X615852Y19807D03*
X616707Y15616D03*
X618900Y33290D03*
X631000Y20107D03*
X630955Y25207D03*
X634757Y20207D03*
X634555Y25307D03*
X623532Y20007D03*
X627231Y19907D03*
X627255Y25107D03*
X619607Y19807D03*
X619730Y24864D03*
X623555Y25107D03*
X642246Y25807D03*
X642451Y20707D03*
X638290Y25674D03*
X638400Y20607D03*
X663200Y20956D03*
X659400Y20474D03*
Y25907D03*
X663202Y25973D03*
X655602Y25223D03*
X655700Y20225D03*
X657900Y30690D03*
G54D37*
X784000Y31000D03*
X782000Y137000D03*
X809000Y149200D03*
G54D38*
X794032Y27032D03*
X804032Y37032D03*
Y47032D03*
X794032Y37032D03*
Y47032D03*
X804032Y57032D03*
X794032D03*
Y67032D03*
G54D35*
X761417Y22798D03*
G54D36*
X804032Y27032D03*
Y67032D03*
G54D28*
X11500Y68500D03*
X12000Y279000D03*
G54D29*
X45669Y77185D03*
%LPD*%
G75*
G36*
G01X788500Y220500D02*
X790500D01*
X791000Y220000D01*
Y208000D01*
X792500Y206500D01*
X794000D01*
X795000Y205500D01*
Y204000D01*
X794500Y203500D01*
Y194000D01*
X800000Y188500D01*
Y187000D01*
X799000Y186000D01*
X786500D01*
X784000Y188500D01*
Y203500D01*
X787500Y207000D01*
Y219500D01*
X788500Y220500D01*
G37*
G54D10*
X14000Y104500D03*
X14400Y98000D03*
X14000Y109500D03*
X15400Y118000D03*
X10900D03*
X15500Y122800D03*
X15000Y127500D03*
X11000Y122800D03*
X10500Y127500D03*
X11500Y163700D03*
Y159000D03*
X7000Y163700D03*
Y159000D03*
X4500Y228900D03*
X4600Y223100D03*
X4500Y234800D03*
X4400Y245100D03*
Y256700D03*
X5000Y275000D03*
X12600Y266900D03*
X15300Y285800D03*
X4900Y285700D03*
X23400Y81550D03*
X25000Y77300D03*
X25200Y286000D03*
X45500Y118000D03*
X50500Y160000D03*
X63200Y194900D03*
X76200Y187200D03*
X70900Y193800D03*
X95500Y93500D03*
X94000Y137500D03*
Y133000D03*
X86500Y177500D03*
X90700Y177050D03*
X92800Y285600D03*
X99500Y91500D03*
Y96000D03*
X104000Y92000D03*
Y96500D03*
X105775Y137349D03*
X103175Y134050D03*
X98500Y137500D03*
X109000Y134050D03*
X98500Y133000D03*
X100000Y267400D03*
X100700Y262900D03*
X97500Y285450D03*
X102000D03*
X106500Y285550D03*
X110700D03*
X114500Y134050D03*
X116500Y211200D03*
X122250Y228750D03*
Y233000D03*
Y237300D03*
Y241500D03*
X128500Y165000D03*
X129500Y252500D03*
X129000Y268000D03*
X136500Y272500D03*
X166500Y241000D03*
X186500Y276500D03*
Y281000D03*
X203100Y252900D03*
X191100Y276600D03*
X190900Y280800D03*
X216261Y74846D03*
X211900Y253000D03*
X207500D03*
X217000Y252900D03*
X212400Y281200D03*
X217000Y281000D03*
X212500Y277000D03*
X208000D03*
X226900Y133300D03*
X233500Y258958D03*
X228000Y259000D03*
X240565Y113365D03*
X238500Y259000D03*
X243000D03*
X258400Y65600D03*
X253000Y267000D03*
X334500Y266300D03*
X334300Y270500D03*
X345089Y73089D03*
X343600Y270500D03*
X646000Y46007D03*
X640000D03*
X654500Y46107D03*
X753500Y24007D03*
Y20007D03*
Y28507D03*
X755500Y16000D03*
X767500Y24007D03*
X760500Y29000D03*
X761000Y16007D03*
X767500Y28507D03*
Y19507D03*
X764200Y44200D03*
X767500Y33207D03*
X764500Y54000D03*
X764300Y49200D03*
X769500Y50000D03*
X761000Y58500D03*
X785830Y188700D03*
X785400Y202800D03*
X789000Y204979D03*
X789200Y214200D03*
Y209800D03*
X784500Y222500D03*
X789000Y223500D03*
X789200Y218700D03*
X786000Y228000D03*
Y232400D03*
X786200Y236900D03*
X786300Y241500D03*
X785000Y245800D03*
Y250200D03*
Y254900D03*
X789910Y187679D03*
X794110D03*
X798310Y187779D03*
X793500Y204979D03*
Y223500D03*
X793200Y228400D03*
Y232600D03*
Y237200D03*
Y242400D03*
X793300Y247200D03*
X795300Y260800D03*
X795400Y251700D03*
X795300Y256500D03*
Y265000D03*
X809200Y209500D03*
Y213700D03*
Y218400D03*
X809100Y228600D03*
Y224400D03*
X808700Y238300D03*
Y234100D03*
Y242900D03*
X809500Y251500D03*
Y257000D03*
X808700Y247100D03*
X809700Y285900D03*
X821900Y273100D03*
X821600Y285500D03*
G54D20*
G01X112800Y225400D02*
X124900D01*
X140500Y241000D01*
X166500D01*
G01X112700Y221200D02*
X125933D01*
X141233Y236500D01*
X146500D01*
G01X240565Y113365D02*
X242200Y111730D01*
Y102131D01*
X241950Y101881D01*
Y99519D01*
X244800Y96669D01*
Y89246D01*
X258300Y75746D01*
Y65700D01*
X258400Y65600D01*
G54D11*
G01X10636Y-27865D02*
G02I-12000J0D01*
G01X14636D02*
X-17364D01*
G01X5486D02*
G02I-6850J0D01*
G01X-1364Y-43865D02*
Y-11865D01*
G01X14636Y-43865D02*
Y-123865D01*
G01D02*
X1309236D01*
G01X14636Y-79365D02*
X1309236D01*
G01X14636Y-43865D02*
X1309236D01*
G01X104900Y248800D02*
X106400Y250300D01*
Y264500D01*
X113400Y271500D01*
X125500D01*
X129000Y268000D01*
G01X100000Y267400D02*
X97100Y264500D01*
Y247000D01*
X97600Y246500D01*
G01X100700Y262900D02*
Y263500D01*
X111900Y274700D01*
X126826D01*
X132196Y269330D01*
Y255196D01*
X129500Y252500D01*
G01X144200Y270700D02*
X137000Y277900D01*
X110500D01*
X100000Y267400D01*
G01X116500Y211200D02*
X120813D01*
X140613Y231000D01*
X146000D01*
G01X183344Y94056D02*
Y86644D01*
X180700Y84000D01*
Y78500D01*
G01X272300Y129442D02*
Y123200D01*
X275000Y120500D01*
X285900D01*
X286500Y119900D01*
G01X286600Y136000D02*
X285600Y135000D01*
X277858D01*
X272300Y129442D01*
G01X521736Y-43865D02*
Y-123865D01*
G01X659236Y-43865D02*
Y-123865D01*
G01X714900Y131900D02*
X714222D01*
X699000Y147122D01*
Y162255D01*
G01X718900Y94000D02*
Y129080D01*
X716080Y131900D01*
X714900D01*
G01X774236Y-43865D02*
Y-123865D01*
G01X941736Y-43865D02*
Y-123865D01*
G01X1111736Y-43865D02*
Y-123865D01*
G01X1309236Y-43865D02*
Y-123865D01*
G01X1341236Y-27865D02*
X1309236D01*
G01X1337236D02*
G02I-12000J0D01*
G01X1332086D02*
G02I-6850J0D01*
G01X1325236Y-43865D02*
Y-11865D01*
X10000Y229500D03*
X16118Y230118D03*
X10194Y243106D03*
X9500Y234200D03*
X16899Y241929D03*
X16300Y236023D03*
X10190Y258510D03*
X10194Y254917D03*
X10190Y246699D03*
X16899Y247834D03*
Y253740D03*
Y259645D03*
X7600Y268100D03*
X16899Y265551D03*
X32800Y120400D03*
X25800Y120300D03*
X29200D03*
X26500Y181800D03*
X33500Y178100D03*
X33150Y181500D03*
X29400Y180000D03*
X23100Y181800D03*
X30000Y196200D03*
X31500Y207500D03*
X40500Y127700D03*
X38500Y148000D03*
X48500D03*
X41000Y152300D03*
Y143300D03*
X46000D03*
Y152300D03*
X43500Y148000D03*
Y138500D03*
X48500D03*
X38500D03*
X45800Y158100D03*
X34800Y198800D03*
Y203700D03*
X37600Y212700D03*
Y207800D03*
X34500Y216000D03*
X40400Y217100D03*
X40700Y224000D03*
X40200Y238300D03*
Y231300D03*
Y245300D03*
X40500Y260000D03*
X40600Y252500D03*
X52500Y96500D03*
Y106500D03*
X57500Y96500D03*
X60000Y101500D03*
X50000D03*
X55000D03*
X57500Y106500D03*
X60000Y111300D03*
X50000D03*
X55000D03*
X54700Y192200D03*
X52700Y184800D03*
X62800Y184300D03*
X50000Y270000D03*
X57800Y264100D03*
X64700Y272500D03*
X57800Y267500D03*
X79115Y60979D03*
X72137Y210237D03*
X79500Y230000D03*
X78700Y259800D03*
X67600Y255800D03*
X75300Y259900D03*
X66300Y259300D03*
X78200Y275600D03*
X66800Y275200D03*
X67000Y263200D03*
X88700Y54400D03*
X85300D03*
X82885Y60979D03*
X94500Y76200D03*
X85898Y200598D03*
X84500Y230000D03*
X89500D03*
X84500Y225000D03*
Y235000D03*
X91400Y270300D03*
X103450Y54400D03*
X100050D03*
X97900Y76200D03*
X95700Y197200D03*
X97100Y189200D03*
X102000Y203200D03*
X99600Y225700D03*
X99328Y235370D03*
X109000Y231400D03*
X97600Y246500D03*
X104900Y248800D03*
X119200Y57400D03*
X115800D03*
X119600Y143300D03*
X120500Y139000D03*
X112800Y225400D03*
X112700Y221200D03*
X131600Y57400D03*
X135000D03*
X133786Y134700D03*
X130300Y135000D03*
X131500Y149000D03*
X136156Y138025D03*
X131762Y141796D03*
X137300Y158900D03*
X132700Y158600D03*
X140800Y158900D03*
X128000Y203300D03*
X144995Y57995D03*
X155290Y48610D03*
X147315Y54400D03*
X150715D03*
X153000Y67800D03*
X147808Y145208D03*
X150804Y158896D03*
X144500Y158900D03*
X150500Y183000D03*
X153500Y210000D03*
X146396Y207675D03*
X142997Y207891D03*
X150000Y210100D03*
X146500Y236500D03*
X146000Y231000D03*
X144200Y270700D03*
X159060Y48610D03*
X170290Y49600D03*
X166463Y54400D03*
X163063D03*
X172300Y107189D03*
X157500Y149025D03*
X167581Y164084D03*
X165900Y181500D03*
X163700Y178900D03*
X165700Y203400D03*
X162000Y226000D03*
X167000D03*
Y221500D03*
X162000D03*
Y230500D03*
X167000D03*
X162000Y235000D03*
X174060Y49600D03*
X186865Y54300D03*
X181800Y54400D03*
X179000D03*
X180700Y78500D03*
X183344Y94056D03*
X181732Y97500D03*
X177500Y209500D03*
X176800Y241600D03*
X189700Y54300D03*
X194075Y80360D03*
X197845D03*
X191500Y94100D03*
X194900Y124200D03*
X198198Y206374D03*
X194800Y206100D03*
X201596Y206504D03*
X210547Y139028D03*
X206790Y139040D03*
X205000Y206500D03*
X205920Y221550D03*
X208800Y219500D03*
X212500D03*
X232591Y43057D03*
X236211D03*
X245385Y40357D03*
X241765D03*
X244400Y50600D03*
X240297Y63400D03*
X244759Y85200D03*
X254600Y41100D03*
X262131Y100959D03*
X263600Y239850D03*
Y252700D03*
X275300Y44900D03*
X278868Y56000D03*
X271000Y57500D03*
X268000D03*
X275900Y88200D03*
X278075Y116475D03*
X272300Y129442D03*
X280400Y129225D03*
X267187Y149800D03*
X273900Y156198D03*
X267456Y160156D03*
X267100Y156200D03*
X272380Y159240D03*
X270500Y156250D03*
X278450Y216800D03*
X267275Y253400D03*
X265500Y249300D03*
X269800Y250700D03*
X267000Y271300D03*
X286800Y57900D03*
X290200D03*
X288100Y99500D03*
X286500Y119900D03*
X286600Y136000D03*
X295900Y154200D03*
X282950Y181350D03*
X281599Y261799D03*
X308200Y57400D03*
X304800D03*
X309400Y82100D03*
X304400Y88400D03*
X301600Y93300D03*
X296531Y133061D03*
X307231Y164059D03*
X297250Y163700D03*
X304400Y224900D03*
X298900Y253300D03*
X309000Y266700D03*
X315800Y57400D03*
X319200D03*
X312400Y79700D03*
X318600Y264300D03*
X331931Y40995D03*
X328303D03*
X331300Y48475D03*
X327577D03*
X333600Y63800D03*
X364600Y44298D03*
X363604Y41042D03*
X373000Y242300D03*
Y236000D03*
Y238900D03*
X379300Y275300D03*
X416128Y272896D03*
X430000Y21500D03*
X424543Y27900D03*
X423000Y43900D03*
X424536Y34800D03*
X424599Y31300D03*
X420500Y257800D03*
X423000Y274000D03*
X426600Y274100D03*
X429900Y274940D03*
X446100Y18700D03*
X440600Y274300D03*
X451300Y21700D03*
X464000Y275200D03*
X460400D03*
X452500D03*
X466500Y272800D03*
X475500Y265900D03*
X479000D03*
X482400Y266200D03*
X498500Y88995D03*
X682600Y114300D03*
X689400Y178900D03*
X689547Y175500D03*
X686700Y187400D03*
X687456Y183944D03*
X718900Y94000D03*
X714900Y131900D03*
X740300Y164700D03*
X733000Y176200D03*
G54D21*
G01X194900Y124200D02*
Y107300D01*
X186200Y98600D01*
Y96100D01*
X187700Y94600D01*
X191000D01*
X191500Y94100D01*
G54D12*
G01X194800Y206100D02*
Y206519D01*
X188997Y212322D01*
X176291D01*
X176168Y212199D01*
X176163Y212198D01*
X167233D01*
X147035Y192000D01*
X136381D01*
X133300Y188919D01*
Y169800D01*
X128500Y165000D01*
X196800Y62600D03*
X502500Y6200D03*
X538300Y15200D03*
X699000Y162255D03*
X799000Y121500D03*
Y125500D03*
X800400Y158500D03*
X799900Y168800D03*
G54D22*
G01X353385Y212898D02*
X352737Y212250D01*
X351382D01*
X350350Y213282D01*
Y216482D01*
X347132Y219700D01*
X344932D01*
X338500Y226132D01*
Y233090D01*
X337493Y234097D01*
Y234452D01*
X337421Y234524D01*
G01X353594Y210707D02*
X352851Y211450D01*
X351050D01*
X349550Y212950D01*
Y216150D01*
X346800Y218900D01*
X344600D01*
X337700Y225800D01*
Y232758D01*
X336891Y233567D01*
X336539D01*
X336502Y233604D01*
G01X334337Y225910D02*
X334408Y225839D01*
X334761D01*
X340600Y220000D01*
Y215106D01*
X341455Y214251D01*
X342681D01*
X343242Y213690D01*
G01X335256Y226830D02*
X335327Y226759D01*
Y226405D01*
X341400Y220332D01*
Y215438D01*
X341787Y215051D01*
X342339D01*
X343198Y215910D01*
G01X347593Y210277D02*
X347120Y210750D01*
X342618D01*
X339000Y214368D01*
Y219100D01*
X336000Y222100D01*
X334200D01*
X331509Y224791D01*
X331184D01*
G01X347664Y212476D02*
X346738Y211550D01*
X342950D01*
X339800Y214700D01*
Y219432D01*
X336332Y222900D01*
X334532D01*
X332146Y225286D01*
Y225668D01*
X332104Y225710D01*
G01X337341Y215731D02*
X336722Y216350D01*
X335350D01*
X334234Y217466D01*
Y218134D01*
X325844Y226524D01*
X325491D01*
X325421Y226594D01*
G01X337307Y217961D02*
X336496Y217150D01*
X335682D01*
X335034Y217798D01*
Y218466D01*
X326411Y227089D01*
Y227443D01*
X326340Y227514D01*
G01X338967Y209455D02*
X338322Y210100D01*
X335800D01*
X333700Y212200D01*
Y215700D01*
X326227Y223173D01*
X325873D01*
G01X338926Y211674D02*
X338152Y210900D01*
X336132D01*
X334500Y212532D01*
Y216032D01*
X326829Y223703D01*
Y224057D01*
X326793Y224093D01*
G01X331658Y212660D02*
X330908Y213410D01*
X328490D01*
X327541Y214359D01*
X326990D01*
X326141Y215207D01*
Y215759D01*
X325293Y216607D01*
X324741D01*
X323893Y217456D01*
Y218007D01*
X321450Y220450D01*
X319750D01*
X319360Y220060D01*
X318160D01*
X317770Y220450D01*
X316650D01*
X316400Y220200D01*
X316300D01*
G01X331616Y214860D02*
X330966Y214210D01*
X328822D01*
X321782Y221250D01*
X316650D01*
X316400Y221500D01*
X316300D01*
G01X316600Y217450D02*
X316850Y217700D01*
X320300D01*
X321300Y216700D01*
Y215468D01*
X328439Y208329D01*
Y207777D01*
X329288Y206929D01*
X329839D01*
X330688Y206080D01*
Y205529D01*
X331536Y204680D01*
X332088D01*
X335185Y201583D01*
X337583D01*
X338534Y200632D01*
Y198966D01*
X338068Y198500D01*
X336556D01*
X335739Y199317D01*
G01X335400Y196300D02*
Y196900D01*
X336200Y197700D01*
X338400D01*
X339334Y198634D01*
Y200964D01*
X337915Y202383D01*
X335517D01*
X322100Y215800D01*
Y217032D01*
X320632Y218500D01*
X316900D01*
X316650Y218750D01*
X316600D01*
G01X436100Y85700D02*
X435900Y85900D01*
X416600D01*
X413200Y89300D01*
Y96578D01*
X414622Y98000D01*
G01X436556Y86800D02*
X436456Y86700D01*
X416932D01*
X414722Y88910D01*
Y90250D01*
G01X411300Y85600D02*
X412800Y84100D01*
X433500D01*
G01X411000Y92100D02*
X409200Y90300D01*
Y84500D01*
X410900Y82800D01*
X421600D01*
G01X418400Y98150D02*
X416580Y96330D01*
Y90200D01*
X418380Y88400D01*
X437000D01*
G01X407500Y84000D02*
X410000Y81500D01*
X428753D01*
X429253Y81000D01*
G01X409600Y80200D02*
X408000D01*
X405600Y82600D01*
Y89100D01*
X407400Y90900D01*
Y91000D01*
G01X417900Y146900D02*
X418800Y150000D01*
X420100Y151300D01*
X430134D01*
X436306Y149800D01*
X437306Y148800D01*
G01X411900Y146800D02*
X412300Y148300D01*
X413574Y150325D01*
X414524Y151275D01*
X415700Y151600D01*
X417600D01*
X419000Y153000D01*
X432600D01*
X437500Y155500D01*
X441600D01*
X444000Y153100D01*
G01X446400Y156400D02*
X421900D01*
X419000Y155000D01*
X417400Y153400D01*
X415900Y152800D01*
X413750Y151950D01*
X408800Y147000D01*
G01X414900D02*
X417850Y150250D01*
X419700Y152100D01*
X430230D01*
X430824Y151956D01*
X437100Y150700D01*
G01X413950Y226994D02*
Y220250D01*
X412100Y218400D01*
G01X412850Y227450D02*
Y225900D01*
X412050Y225100D01*
G01X437200Y91691D02*
X435109Y89600D01*
X420000D01*
X418300Y91300D01*
G01X422078Y97678D02*
X427696Y92060D01*
X430460D01*
X435009Y96609D01*
G01X436500Y94309D02*
X433191Y91000D01*
X422300D01*
X422000Y91300D01*
G01X436800Y135700D02*
X436548Y135448D01*
X428352D01*
X421800Y142000D01*
Y142100D01*
X421500Y142400D01*
G01X420861Y146923D02*
X421747Y147809D01*
X424241D01*
X425582Y149150D01*
X431283D01*
X436870Y143563D01*
X440305D01*
X441361Y142507D01*
X444376D01*
X445429Y143560D01*
X462978D01*
X462997Y143541D01*
X463100D01*
G01X420861Y149687D02*
X421939Y148609D01*
X423909D01*
X425250Y149950D01*
X431615D01*
X437202Y144363D01*
X440637D01*
X441693Y143307D01*
X444044D01*
X445097Y144360D01*
X462646D01*
X462927Y144641D01*
X463050D01*
G01X435700Y137500D02*
X434852Y138348D01*
X431941D01*
X430893Y137300D01*
X427700D01*
X426600Y138400D01*
Y142757D01*
X427600Y143757D01*
Y143841D01*
G01X463941Y141241D02*
X437441D01*
X436860Y140660D01*
X434403D01*
X433400Y141663D01*
Y145700D01*
X431900Y147200D01*
X427100D01*
X427000Y147100D01*
X426900D01*
G01X463700Y139300D02*
X463500Y139500D01*
X434431D01*
X432500Y141431D01*
Y143000D01*
X431100Y145500D01*
G01X460100Y123100D02*
X461500D01*
X466359Y118241D01*
G01X462300Y119600D02*
X461400Y120500D01*
X454900D01*
X453000Y122400D01*
Y123300D01*
G01X452200Y129800D02*
X454200Y127800D01*
X464500D01*
X468219Y124081D01*
G01X456000Y133500D02*
X457700Y131800D01*
X465100D01*
X468159Y128741D01*
G01X468259Y131041D02*
X466000Y133300D01*
X463500D01*
X463100Y133700D01*
G01X467759Y126441D02*
X464300Y129900D01*
X459700D01*
G01X466300Y120541D02*
X462091Y124750D01*
X457850D01*
X456500Y126100D01*
G01X467759Y121641D02*
X467618Y121500D01*
X466473D01*
X463200Y124773D01*
Y126200D01*
G01X466200Y166300D02*
X463200Y169300D01*
X452800D01*
X451000Y171100D01*
G01X465900Y168600D02*
X463400Y171100D01*
X458000D01*
G01X467269Y170900D02*
X466542Y171627D01*
Y171626D01*
X464968Y173200D01*
X454700D01*
X453000Y174900D01*
G01X467442Y172000D02*
X467142Y172300D01*
X467000D01*
X465300Y174000D01*
X460900D01*
X460000Y174900D01*
G01X457400Y197000D02*
X462400D01*
X467164Y201764D01*
G01X467364Y199464D02*
X463100Y195200D01*
X452200D01*
X450400Y197000D01*
G01X468600Y196064D02*
X468040D01*
X463688Y191712D01*
X454988D01*
X453400Y193300D01*
G01X468008Y197164D02*
X463356Y192512D01*
X461188D01*
X460400Y193300D01*
G01X475164Y191464D02*
X471000Y187300D01*
X464200D01*
X462500Y189000D01*
G01X465964Y206364D02*
X460300Y200700D01*
X459500D01*
G01X466564Y204064D02*
X461500Y199000D01*
X454200D01*
X452500Y200700D01*
G01X479200Y181200D02*
X478600Y181800D01*
X471300D01*
G01X477900Y178900D02*
X476800Y180000D01*
X466100D01*
X464300Y181800D01*
G01X473900Y178200D02*
X475500Y176600D01*
G01X475100Y174300D02*
X472700Y176700D01*
X468400D01*
X466900Y178200D01*
G01X474764Y193764D02*
X470000Y189000D01*
X469500D01*
G01X477800Y189100D02*
X474200Y185500D01*
X473100D01*
G01X477700Y186500D02*
X474900Y183700D01*
X467800D01*
X466000Y185500D01*
G54D13*
X304149Y128349D03*
X309500Y132925D03*
X306961Y153717D03*
X306696Y158610D03*
X325081Y100631D03*
X322075Y100650D03*
X326162Y91438D03*
X315950Y98650D03*
X323300Y147046D03*
X319704Y162804D03*
X323165Y171937D03*
X324436Y175705D03*
X311460Y172078D03*
X319942Y180524D03*
X312829Y181940D03*
X323800Y192150D03*
X323789Y188117D03*
X320029Y184300D03*
X326500Y187900D03*
X311900Y188070D03*
X322256Y198618D03*
X323331Y196696D03*
X325642Y202325D03*
X321600Y208700D03*
Y211000D03*
X317200Y213100D03*
Y215300D03*
X328000Y92700D03*
X338470Y138177D03*
X327696Y146108D03*
X329800Y150800D03*
X331000Y164500D03*
X333000Y158300D03*
X339747Y164478D03*
X333842Y177224D03*
X332300Y173900D03*
X339875Y177303D03*
X334715Y180900D03*
X332100Y185600D03*
X338000Y185700D03*
X335000Y185500D03*
X335400Y196300D03*
X332800Y187700D03*
X335739Y199317D03*
X336500Y204600D03*
X338926Y211674D03*
X338967Y209455D03*
X331658Y212660D03*
X327216Y203902D03*
X337307Y217961D03*
X331616Y214860D03*
X337341Y215731D03*
X350550Y153280D03*
X344300Y153800D03*
X344090Y156690D03*
X355300Y174600D03*
X347200Y174300D03*
X352200Y171800D03*
X350000Y177700D03*
X345562Y178700D03*
X353321Y180128D03*
X356900Y186100D03*
X342760Y187810D03*
X349751Y187241D03*
X353594Y210707D03*
X347593Y210277D03*
X353385Y212898D03*
X343242Y213690D03*
X347664Y212476D03*
X343198Y215910D03*
X371900Y85400D03*
X371950Y92500D03*
X361700Y143300D03*
X361500Y149500D03*
X358500Y155700D03*
X361500Y168500D03*
X357966Y217516D03*
X359827Y216341D03*
X383350Y83350D03*
X383450Y90500D03*
X387200D03*
X387100Y83500D03*
X375800D03*
Y90500D03*
X379500Y83302D03*
Y90600D03*
X380475Y137016D03*
X374200Y136994D03*
X380398Y146568D03*
X383548D03*
X374200Y140144D03*
X380400Y152700D03*
X383575Y149603D03*
X380522Y149564D03*
X377476Y149688D03*
X383693Y171424D03*
X393000Y152663D03*
X402900Y149663D03*
X403080Y146931D03*
X399198Y146468D03*
X396192Y146444D03*
X392998Y149718D03*
X399198Y149618D03*
X396182Y149674D03*
X396200Y152763D03*
X396300Y162100D03*
X399300Y152863D03*
Y155963D03*
X393028Y162059D03*
X393198Y158940D03*
X403078Y152922D03*
X402373Y155952D03*
X399298Y162090D03*
X402505Y159133D03*
X396148Y158940D03*
X399298D03*
X397100Y181000D03*
X395700Y213600D03*
X407500Y84000D03*
X407400Y91000D03*
X411300Y85600D03*
X414722Y90250D03*
X418300Y91300D03*
X418400Y98150D03*
X411000Y92100D03*
X414622Y98000D03*
X413100Y121800D03*
X412462Y126300D03*
X414900Y147000D03*
X417900Y146900D03*
X408800Y147000D03*
X411900Y146800D03*
X406000Y150200D03*
X407500Y152100D03*
X410400Y152000D03*
X407500Y157600D03*
X412900Y157800D03*
X407400Y154863D03*
X406100Y159500D03*
X415100Y158100D03*
X410272Y154794D03*
X408600Y159600D03*
X411600D03*
X404558Y154835D03*
X412100Y190400D03*
X412200Y192600D03*
X408200Y226900D03*
X408100Y220500D03*
X404400Y228600D03*
Y222300D03*
X415600Y222700D03*
X415800Y215900D03*
X412050Y225100D03*
X412100Y218400D03*
X422078Y97678D03*
X422000Y91300D03*
X429500Y93800D03*
X427600Y143841D03*
X421500Y142400D03*
X426900Y147100D03*
X431100Y145500D03*
X420861Y149687D03*
Y146923D03*
X434500Y160037D03*
X419550Y222700D03*
X419600Y216200D03*
X459800Y118800D03*
X453000Y118700D03*
X459700Y129900D03*
X452200Y129800D03*
X463100Y133700D03*
X456000Y133500D03*
X460100Y123100D03*
X453000Y123300D03*
X463200Y126200D03*
X456500Y126100D03*
X461200Y167400D03*
X454200D03*
X464300Y181800D03*
X458000Y171100D03*
X451000D03*
X460000Y174900D03*
X453000D03*
X457400Y197000D03*
X450400D03*
X462500Y189000D03*
X460400Y193300D03*
X453400D03*
X459500Y200700D03*
X452500D03*
X473900Y178200D03*
X466900D03*
X471300Y181800D03*
X473100Y185500D03*
X466000D03*
X469500Y189000D03*
X528525Y12549D03*
X542100Y15107D03*
X530700Y15407D03*
X536485Y22907D03*
X533200D03*
X542407Y30882D03*
X532350Y30807D03*
X529120Y32575D03*
X544860Y12407D03*
X545928Y31047D03*
X550200Y255500D03*
X551000Y252056D03*
X548800Y271000D03*
X551937Y272789D03*
X555641Y262489D03*
X561419Y254850D03*
X565054Y254773D03*
X560600Y270300D03*
X564100Y271100D03*
X558926Y262489D03*
X587940Y12417D03*
X594600Y6707D03*
X601704Y22907D03*
X594400Y36207D03*
X589300Y33007D03*
X610952Y12307D03*
X614700Y14107D03*
X607300Y14507D03*
X604989Y22907D03*
X615951Y22356D03*
X610944Y33333D03*
X607800Y30407D03*
X615044Y33190D03*
X618877Y30790D03*
X633500Y12406D03*
X624000D03*
X634757Y22707D03*
X623480Y22564D03*
X631007Y22707D03*
X619700Y22307D03*
X627257Y22407D03*
X624100Y33190D03*
X633449D03*
X641745Y12367D03*
X645200Y27707D03*
X646800Y17607D03*
X642257Y23307D03*
X638507Y23183D03*
X650200Y33307D03*
X641900Y31507D03*
X642802Y252186D03*
X645920Y254130D03*
X642937Y273089D03*
X646360Y271530D03*
X648948Y262489D03*
X657897Y12504D03*
X651316Y12360D03*
X664212Y16356D03*
X663300Y23454D03*
X662916Y28457D03*
X655592Y22723D03*
X659400Y23207D03*
X657900Y33190D03*
X659437Y246389D03*
X665500Y252189D03*
X659500Y274000D03*
X665100Y272700D03*
X652233Y262489D03*
X669600Y17907D03*
X670200Y254700D03*
X673770Y254752D03*
X669700Y270900D03*
X672800Y272700D03*
X676113Y262489D03*
X679398D03*
X690102Y12502D03*
X692200Y15357D03*
X695029Y22853D03*
X693300Y30607D03*
X689624Y30383D03*
X682800Y254900D03*
X685382Y252200D03*
X682481Y270700D03*
X685100Y273100D03*
X702000Y12607D03*
X705031Y14515D03*
X698277Y22855D03*
X704430Y33313D03*
X701800Y30807D03*
X727000Y30407D03*
X742200Y12407D03*
X728010Y12857D03*
X739000Y14407D03*
X731169Y14584D03*
X736091Y23607D03*
X732806D03*
X742100Y33007D03*
X740200Y29907D03*
X730500D03*
X747441Y33007D03*
X753000Y272100D03*
G54D23*
G01X70851Y-113865D02*
Y-96365D01*
G01X80021D02*
Y-113865D01*
G01Y-105115D02*
X70851D01*
G01X92936Y-113865D02*
X91626Y-113573D01*
X90316Y-112407D01*
X89442Y-110365D01*
X89006Y-108032D01*
X89442Y-105698D01*
X90316Y-103657D01*
X91626Y-102490D01*
X92936Y-102199D01*
X94246Y-102490D01*
X95556Y-103657D01*
X96429Y-105698D01*
X96648Y-108032D01*
X96429Y-110365D01*
X95556Y-112407D01*
X94246Y-113573D01*
X92936Y-113865D01*
G01X106724D02*
Y-102199D01*
G01Y-105115D02*
X107598Y-103657D01*
X108908Y-102490D01*
X110654Y-102199D01*
X112182Y-102490D01*
X113493Y-103657D01*
X114148Y-105698D01*
Y-113865D01*
G01X124661Y-105990D02*
X131648D01*
X130993Y-103948D01*
X129901Y-102782D01*
X128373Y-102199D01*
X126844Y-102490D01*
X125534Y-103365D01*
X124661Y-105407D01*
X124224Y-107157D01*
Y-108907D01*
X124661Y-110657D01*
X125753Y-112407D01*
X127063Y-113573D01*
X128591Y-113865D01*
X130119Y-113282D01*
X131648Y-111532D01*
G01X140851Y-119115D02*
X142161Y-119698D01*
X143908Y-119115D01*
X144999Y-117949D01*
X145873Y-116490D01*
X147182Y-111824D01*
X150021Y-102199D01*
G01X143034D02*
X147182Y-111824D01*
G01X182182Y-104532D02*
X183056Y-103657D01*
X183711Y-102199D01*
X184148Y-100156D01*
X183711Y-98407D01*
X182838Y-97240D01*
X181309Y-96365D01*
X175414D01*
Y-113865D01*
X182619D01*
X184148Y-112699D01*
X185021Y-110948D01*
X185458Y-108907D01*
X185021Y-106865D01*
X183711Y-105115D01*
X182182Y-104532D01*
X175414D01*
G01X201866Y-113865D02*
Y-102199D01*
G01Y-104240D02*
X200993Y-103074D01*
X199682Y-102490D01*
X198154Y-102199D01*
X196626Y-102782D01*
X195316Y-103948D01*
X194442Y-105698D01*
X194006Y-108032D01*
X194442Y-110365D01*
X195316Y-112115D01*
X196626Y-113282D01*
X198154Y-113865D01*
X199682Y-113573D01*
X200993Y-112699D01*
X201866Y-111532D01*
G01X219366Y-96365D02*
Y-113865D01*
G01Y-111241D02*
X218493Y-112699D01*
X217182Y-113573D01*
X215654Y-113865D01*
X213908Y-113282D01*
X212598Y-111824D01*
X211724Y-110074D01*
X211506Y-108032D01*
X211724Y-105990D01*
X212598Y-104240D01*
X213908Y-102782D01*
X215654Y-102199D01*
X217182Y-102490D01*
X218274Y-103074D01*
X219366Y-104240D01*
G01X229879Y-118240D02*
X231408Y-119407D01*
X233154Y-119698D01*
X234682Y-119407D01*
X235993Y-117949D01*
X236866Y-115907D01*
Y-102199D01*
G01Y-104532D02*
X235993Y-103365D01*
X234682Y-102490D01*
X233154Y-102199D01*
X231408Y-102782D01*
X230316Y-103948D01*
X229442Y-105990D01*
X229006Y-108032D01*
X229224Y-109782D01*
X230098Y-111824D01*
X231408Y-113282D01*
X233154Y-113865D01*
X234464Y-113573D01*
X235993Y-112407D01*
X236866Y-111241D01*
G01X247161Y-105990D02*
X254148D01*
X253493Y-103948D01*
X252401Y-102782D01*
X250873Y-102199D01*
X249344Y-102490D01*
X248034Y-103365D01*
X247161Y-105407D01*
X246724Y-107157D01*
Y-108907D01*
X247161Y-110657D01*
X248253Y-112407D01*
X249563Y-113573D01*
X251091Y-113865D01*
X252619Y-113282D01*
X254148Y-111532D01*
G01X264879Y-113865D02*
Y-102199D01*
G01Y-104532D02*
X265971Y-103365D01*
X267063Y-102490D01*
X268591Y-102199D01*
X269682Y-102490D01*
X270993Y-103365D01*
G01X298569Y-113865D02*
Y-96365D01*
X303809D01*
X305556Y-97240D01*
X306866Y-99282D01*
X307303Y-101615D01*
X306866Y-103948D01*
X305774Y-105698D01*
X303809Y-106574D01*
X298569D01*
G01X324366Y-113865D02*
Y-102199D01*
G01Y-104240D02*
X323493Y-103074D01*
X322182Y-102490D01*
X320654Y-102199D01*
X319126Y-102782D01*
X317816Y-103948D01*
X316942Y-105698D01*
X316506Y-108032D01*
X316942Y-110365D01*
X317816Y-112115D01*
X319126Y-113282D01*
X320654Y-113865D01*
X322182Y-113573D01*
X323493Y-112699D01*
X324366Y-111532D01*
G01X334224Y-113865D02*
Y-102199D01*
G01Y-105115D02*
X335098Y-103657D01*
X336408Y-102490D01*
X338154Y-102199D01*
X339682Y-102490D01*
X340993Y-103657D01*
X341648Y-105698D01*
Y-113865D01*
G01X355436Y-96365D02*
Y-113865D01*
G01X352379Y-102199D02*
X358493D01*
G01X369224Y-113865D02*
Y-96365D01*
G01Y-104823D02*
X370316Y-103365D01*
X371408Y-102490D01*
X373154Y-102199D01*
X374464Y-102490D01*
X375993Y-103657D01*
X376648Y-105407D01*
Y-113865D01*
G01X387161Y-105990D02*
X394148D01*
X393493Y-103948D01*
X392401Y-102782D01*
X390873Y-102199D01*
X389344Y-102490D01*
X388034Y-103365D01*
X387161Y-105407D01*
X386724Y-107157D01*
Y-108907D01*
X387161Y-110657D01*
X388253Y-112407D01*
X389563Y-113573D01*
X391091Y-113865D01*
X392619Y-113282D01*
X394148Y-111532D01*
G01X404879Y-113865D02*
Y-102199D01*
G01Y-104532D02*
X405971Y-103365D01*
X407063Y-102490D01*
X408591Y-102199D01*
X409682Y-102490D01*
X410993Y-103365D01*
G01X437259Y-113865D02*
Y-96365D01*
X442936Y-110948D01*
X448613Y-96365D01*
Y-113865D01*
G01X462182Y-104532D02*
X463056Y-103657D01*
X463711Y-102199D01*
X464148Y-100156D01*
X463711Y-98407D01*
X462838Y-97240D01*
X461309Y-96365D01*
X455414D01*
Y-113865D01*
X462619D01*
X464148Y-112699D01*
X465021Y-110948D01*
X465458Y-108907D01*
X465021Y-106865D01*
X463711Y-105115D01*
X462182Y-104532D01*
X455414D01*
G01X227259Y-68865D02*
Y-51365D01*
X232936Y-65948D01*
X238613Y-51365D01*
Y-68865D01*
G01X250436D02*
X249126Y-68573D01*
X247816Y-67407D01*
X246942Y-65365D01*
X246506Y-63032D01*
X246942Y-60698D01*
X247816Y-58657D01*
X249126Y-57490D01*
X250436Y-57199D01*
X251746Y-57490D01*
X253056Y-58657D01*
X253929Y-60698D01*
X254148Y-63032D01*
X253929Y-65365D01*
X253056Y-67407D01*
X251746Y-68573D01*
X250436Y-68865D01*
G01X271866Y-51365D02*
Y-68865D01*
G01Y-66241D02*
X270993Y-67699D01*
X269682Y-68573D01*
X268154Y-68865D01*
X266408Y-68282D01*
X265098Y-66824D01*
X264224Y-65074D01*
X264006Y-63032D01*
X264224Y-60990D01*
X265098Y-59240D01*
X266408Y-57782D01*
X268154Y-57199D01*
X269682Y-57490D01*
X270774Y-58074D01*
X271866Y-59240D01*
G01X282161Y-60990D02*
X289148D01*
X288493Y-58948D01*
X287401Y-57782D01*
X285873Y-57199D01*
X284344Y-57490D01*
X283034Y-58365D01*
X282161Y-60407D01*
X281724Y-62157D01*
Y-63907D01*
X282161Y-65657D01*
X283253Y-67407D01*
X284563Y-68573D01*
X286091Y-68865D01*
X287619Y-68282D01*
X289148Y-66532D01*
G01X302936Y-68865D02*
Y-51365D01*
G01X542319Y-68865D02*
Y-51365D01*
X547559D01*
X549306Y-52240D01*
X550616Y-54282D01*
X551053Y-56615D01*
X550616Y-58948D01*
X549524Y-60698D01*
X547559Y-61574D01*
X542319D01*
G01X568989Y-52824D02*
X567679Y-51948D01*
X566151Y-51365D01*
X564404D01*
X562439Y-52240D01*
X560911Y-53698D01*
X559819Y-55449D01*
X558946Y-58365D01*
X558727Y-60990D01*
X559164Y-63615D01*
X559819Y-65365D01*
X561129Y-67115D01*
X562658Y-68282D01*
X564186Y-68865D01*
X565714D01*
X567243Y-68282D01*
X568553Y-67407D01*
X569645Y-66241D01*
G01X583432Y-59532D02*
X584306Y-58657D01*
X584961Y-57199D01*
X585398Y-55156D01*
X584961Y-53407D01*
X584088Y-52240D01*
X582559Y-51365D01*
X576664D01*
Y-68865D01*
X583869D01*
X585398Y-67699D01*
X586271Y-65948D01*
X586708Y-63907D01*
X586271Y-61865D01*
X584961Y-60115D01*
X583432Y-59532D01*
X576664D01*
G01X592636Y-74698D02*
X605736D01*
G01X611664Y-68865D02*
Y-51365D01*
X621708Y-68865D01*
Y-51365D01*
G01X634186Y-68865D02*
X632439Y-68573D01*
X630911Y-67407D01*
X629601Y-65657D01*
X628727Y-63615D01*
X628291Y-61282D01*
Y-58948D01*
X628727Y-56615D01*
X629601Y-54573D01*
X630911Y-52824D01*
X632439Y-51657D01*
X634186Y-51365D01*
X635932Y-51657D01*
X637461Y-52824D01*
X638771Y-54573D01*
X639645Y-56615D01*
X640081Y-58948D01*
Y-61282D01*
X639645Y-63615D01*
X638771Y-65657D01*
X637461Y-67407D01*
X635932Y-68573D01*
X634186Y-68865D01*
G01X555436Y-113865D02*
Y-96365D01*
X552816Y-99865D01*
G01Y-113865D02*
X558056D01*
G01X568133Y-110365D02*
X569442Y-112407D01*
X571189Y-113573D01*
X573154Y-113865D01*
X574901Y-113573D01*
X576648Y-112115D01*
X577739Y-110365D01*
X577958Y-108615D01*
X577521Y-106574D01*
X575993Y-105115D01*
X574464Y-104532D01*
X572499D01*
G01X574464D02*
X575774Y-103657D01*
X576866Y-102199D01*
X577303Y-100449D01*
X576866Y-98698D01*
X575774Y-97240D01*
X573809Y-96365D01*
X571844Y-96657D01*
X569879Y-97824D01*
G01X590436Y-113865D02*
Y-96365D01*
X587816Y-99865D01*
G01Y-113865D02*
X593056D01*
G01X603133Y-110365D02*
X604442Y-112407D01*
X606189Y-113573D01*
X608154Y-113865D01*
X609901Y-113573D01*
X611648Y-112115D01*
X612739Y-110365D01*
X612958Y-108615D01*
X612521Y-106574D01*
X610993Y-105115D01*
X609464Y-104532D01*
X607499D01*
G01X609464D02*
X610774Y-103657D01*
X611866Y-102199D01*
X612303Y-100449D01*
X611866Y-98698D01*
X610774Y-97240D01*
X608809Y-96365D01*
X606844Y-96657D01*
X604879Y-97824D01*
G01X625436Y-96365D02*
X623689Y-96948D01*
X622379Y-98407D01*
X621506Y-100156D01*
X620851Y-102490D01*
X620633Y-105115D01*
X620851Y-107740D01*
X621506Y-110074D01*
X622379Y-111824D01*
X623689Y-113282D01*
X625436Y-113865D01*
X627182Y-113282D01*
X628493Y-111824D01*
X629366Y-110074D01*
X630021Y-107740D01*
X630239Y-105115D01*
X630021Y-102490D01*
X629366Y-100156D01*
X628493Y-98407D01*
X627182Y-96948D01*
X625436Y-96365D01*
G01X685027Y-51365D02*
X690486Y-68865D01*
X695945Y-51365D01*
G01X712353Y-68865D02*
X703619D01*
Y-51365D01*
X712353D01*
G01X708859Y-59823D02*
X703619D01*
G01X721119Y-68865D02*
Y-51365D01*
X726578D01*
X728324Y-52240D01*
X729416Y-53407D01*
X729853Y-55740D01*
X729416Y-58074D01*
X728106Y-59532D01*
X726578Y-60407D01*
X721119D01*
G01X726578D02*
X729853Y-68865D01*
G01X742986Y-69448D02*
X742549Y-69157D01*
Y-68573D01*
X742986Y-68282D01*
X743423Y-68573D01*
Y-69157D01*
X742986Y-69448D01*
G01X707986Y-113865D02*
Y-96365D01*
X705366Y-99865D01*
G01Y-113865D02*
X710606D01*
G01X727232Y-104532D02*
X728106Y-103657D01*
X728761Y-102199D01*
X729198Y-100156D01*
X728761Y-98407D01*
X727888Y-97240D01*
X726359Y-96365D01*
X720464D01*
Y-113865D01*
X727669D01*
X729198Y-112699D01*
X730071Y-110948D01*
X730508Y-108907D01*
X730071Y-106865D01*
X728761Y-105115D01*
X727232Y-104532D01*
X720464D01*
G01X818569Y-51365D02*
Y-68865D01*
X827303D01*
G01X844366D02*
Y-57199D01*
G01Y-59240D02*
X843493Y-58074D01*
X842182Y-57490D01*
X840654Y-57199D01*
X839126Y-57782D01*
X837816Y-58948D01*
X836942Y-60698D01*
X836506Y-63032D01*
X836942Y-65365D01*
X837816Y-67115D01*
X839126Y-68282D01*
X840654Y-68865D01*
X842182Y-68573D01*
X843493Y-67699D01*
X844366Y-66532D01*
G01X853351Y-74115D02*
X854661Y-74698D01*
X856408Y-74115D01*
X857499Y-72949D01*
X858373Y-71490D01*
X859682Y-66824D01*
X862521Y-57199D01*
G01X855534D02*
X859682Y-66824D01*
G01X872161Y-60990D02*
X879148D01*
X878493Y-58948D01*
X877401Y-57782D01*
X875873Y-57199D01*
X874344Y-57490D01*
X873034Y-58365D01*
X872161Y-60407D01*
X871724Y-62157D01*
Y-63907D01*
X872161Y-65657D01*
X873253Y-67407D01*
X874563Y-68573D01*
X876091Y-68865D01*
X877619Y-68282D01*
X879148Y-66532D01*
G01X889879Y-68865D02*
Y-57199D01*
G01Y-59532D02*
X890971Y-58365D01*
X892063Y-57490D01*
X893591Y-57199D01*
X894682Y-57490D01*
X895993Y-58365D01*
G01X844819Y-96365D02*
Y-113865D01*
X853553D01*
G01X861883Y-110365D02*
X863192Y-112407D01*
X864939Y-113573D01*
X866904Y-113865D01*
X868651Y-113573D01*
X870398Y-112115D01*
X871489Y-110365D01*
X871708Y-108615D01*
X871271Y-106574D01*
X869743Y-105115D01*
X868214Y-104532D01*
X866249D01*
G01X868214D02*
X869524Y-103657D01*
X870616Y-102199D01*
X871053Y-100449D01*
X870616Y-98698D01*
X869524Y-97240D01*
X867559Y-96365D01*
X865594Y-96657D01*
X863629Y-97824D01*
G01X943619Y-110365D02*
X944711Y-112115D01*
X946021Y-113282D01*
X947549Y-113865D01*
X949296Y-113282D01*
X950606Y-112115D01*
X951916Y-110365D01*
X952353Y-108032D01*
Y-96365D01*
G01X965486Y-113865D02*
X963739Y-113573D01*
X962211Y-112407D01*
X960901Y-110657D01*
X960027Y-108615D01*
X959591Y-106282D01*
Y-103948D01*
X960027Y-101615D01*
X960901Y-99573D01*
X962211Y-97824D01*
X963739Y-96657D01*
X965486Y-96365D01*
X967232Y-96657D01*
X968761Y-97824D01*
X970071Y-99573D01*
X970945Y-101615D01*
X971381Y-103948D01*
Y-106282D01*
X970945Y-108615D01*
X970071Y-110657D01*
X968761Y-112407D01*
X967232Y-113573D01*
X965486Y-113865D01*
G01X978401Y-111532D02*
X980148Y-112990D01*
X982113Y-113865D01*
X983859D01*
X985606Y-112990D01*
X986916Y-111532D01*
X987571Y-109490D01*
X987134Y-107449D01*
X986043Y-105698D01*
X984078Y-104532D01*
X981458Y-103948D01*
X979929Y-102782D01*
X979274Y-100740D01*
X979711Y-98698D01*
X980803Y-97240D01*
X982331Y-96365D01*
X983859D01*
X985388Y-96948D01*
X986698Y-98407D01*
G01X1004853Y-113865D02*
X996119D01*
Y-96365D01*
X1004853D01*
G01X1001359Y-104823D02*
X996119D01*
G01X1013619Y-113865D02*
Y-96365D01*
X1018859D01*
X1020606Y-97240D01*
X1021916Y-99282D01*
X1022353Y-101615D01*
X1021916Y-103948D01*
X1020824Y-105698D01*
X1018859Y-106574D01*
X1013619D01*
G01X1030901Y-113865D02*
Y-96365D01*
G01X1040071D02*
Y-113865D01*
G01Y-105115D02*
X1030901D01*
G01X1066119Y-96365D02*
Y-113865D01*
X1074853D01*
G01X1082527D02*
X1087986Y-96365D01*
X1093445Y-113865D01*
G01X1091479Y-107740D02*
X1084492D01*
G01X1100683Y-96365D02*
Y-108907D01*
X1101556Y-111532D01*
X1103303Y-113282D01*
X1105486Y-113865D01*
X1107669Y-113282D01*
X1109416Y-111532D01*
X1110289Y-108907D01*
Y-96365D01*
G01X960683Y-68865D02*
Y-51365D01*
X965049D01*
X966796Y-52240D01*
X968106Y-53407D01*
X969198Y-55156D01*
X970071Y-57199D01*
X970289Y-60115D01*
X970071Y-63032D01*
X969198Y-65074D01*
X968106Y-66824D01*
X966796Y-67990D01*
X965049Y-68865D01*
X960683D01*
G01X979711Y-60990D02*
X986698D01*
X986043Y-58948D01*
X984951Y-57782D01*
X983423Y-57199D01*
X981894Y-57490D01*
X980584Y-58365D01*
X979711Y-60407D01*
X979274Y-62157D01*
Y-63907D01*
X979711Y-65657D01*
X980803Y-67407D01*
X982113Y-68573D01*
X983641Y-68865D01*
X985169Y-68282D01*
X986698Y-66532D01*
G01X997211Y-66824D02*
X998303Y-67990D01*
X999831Y-68865D01*
X1001141D01*
X1002451Y-68282D01*
X1003324Y-67407D01*
X1003761Y-66241D01*
X1003543Y-64490D01*
X1002669Y-63615D01*
X998739Y-61865D01*
X997866Y-59823D01*
X998303Y-58365D01*
X999176Y-57490D01*
X1000486Y-57199D01*
X1001796Y-57490D01*
X1003106Y-58365D01*
G01X1017986Y-57199D02*
Y-68865D01*
G01Y-52532D02*
X1017549Y-52240D01*
Y-51657D01*
X1017986Y-51365D01*
X1018423Y-51657D01*
Y-52240D01*
X1017986Y-52532D01*
G01X1032429Y-73240D02*
X1033958Y-74407D01*
X1035704Y-74698D01*
X1037232Y-74407D01*
X1038543Y-72949D01*
X1039416Y-70907D01*
Y-57199D01*
G01Y-59532D02*
X1038543Y-58365D01*
X1037232Y-57490D01*
X1035704Y-57199D01*
X1033958Y-57782D01*
X1032866Y-58948D01*
X1031992Y-60990D01*
X1031556Y-63032D01*
X1031774Y-64782D01*
X1032648Y-66824D01*
X1033958Y-68282D01*
X1035704Y-68865D01*
X1037014Y-68573D01*
X1038543Y-67407D01*
X1039416Y-66241D01*
G01X1049274Y-68865D02*
Y-57199D01*
G01Y-60115D02*
X1050148Y-58657D01*
X1051458Y-57490D01*
X1053204Y-57199D01*
X1054732Y-57490D01*
X1056043Y-58657D01*
X1056698Y-60698D01*
Y-68865D01*
G01X1067211Y-60990D02*
X1074198D01*
X1073543Y-58948D01*
X1072451Y-57782D01*
X1070923Y-57199D01*
X1069394Y-57490D01*
X1068084Y-58365D01*
X1067211Y-60407D01*
X1066774Y-62157D01*
Y-63907D01*
X1067211Y-65657D01*
X1068303Y-67407D01*
X1069613Y-68573D01*
X1071141Y-68865D01*
X1072669Y-68282D01*
X1074198Y-66532D01*
G01X1084929Y-68865D02*
Y-57199D01*
G01Y-59532D02*
X1086021Y-58365D01*
X1087113Y-57490D01*
X1088641Y-57199D01*
X1089732Y-57490D01*
X1091043Y-58365D01*
G01X1131686Y-113865D02*
Y-96365D01*
X1129066Y-99865D01*
G01Y-113865D02*
X1134306D01*
G01X1149186D02*
Y-96365D01*
X1146566Y-99865D01*
G01Y-113865D02*
X1151806D01*
G01X1162756Y-114448D02*
X1170616Y-96365D01*
G01X1184186Y-113865D02*
Y-96365D01*
X1181566Y-99865D01*
G01Y-113865D02*
X1186806D01*
G01X1196883Y-110365D02*
X1198192Y-112407D01*
X1199939Y-113573D01*
X1201904Y-113865D01*
X1203651Y-113573D01*
X1205398Y-112115D01*
X1206489Y-110365D01*
X1206708Y-108615D01*
X1206271Y-106574D01*
X1204743Y-105115D01*
X1203214Y-104532D01*
X1201249D01*
G01X1203214D02*
X1204524Y-103657D01*
X1205616Y-102199D01*
X1206053Y-100449D01*
X1205616Y-98698D01*
X1204524Y-97240D01*
X1202559Y-96365D01*
X1200594Y-96657D01*
X1198629Y-97824D01*
G01X1215256Y-114448D02*
X1223116Y-96365D01*
G01X1232538Y-99282D02*
X1233848Y-97532D01*
X1235376Y-96657D01*
X1237123Y-96365D01*
X1239306Y-96948D01*
X1240834Y-98407D01*
X1241271Y-100156D01*
X1241053Y-101907D01*
X1240179Y-103365D01*
X1235813Y-106282D01*
X1233848Y-108323D01*
X1232538Y-111241D01*
X1232101Y-113865D01*
X1241271D01*
G01X1254186Y-96365D02*
X1252439Y-96948D01*
X1251129Y-98407D01*
X1250256Y-100156D01*
X1249601Y-102490D01*
X1249383Y-105115D01*
X1249601Y-107740D01*
X1250256Y-110074D01*
X1251129Y-111824D01*
X1252439Y-113282D01*
X1254186Y-113865D01*
X1255932Y-113282D01*
X1257243Y-111824D01*
X1258116Y-110074D01*
X1258771Y-107740D01*
X1258989Y-105115D01*
X1258771Y-102490D01*
X1258116Y-100156D01*
X1257243Y-98407D01*
X1255932Y-96948D01*
X1254186Y-96365D01*
G01X1271686Y-113865D02*
Y-96365D01*
X1269066Y-99865D01*
G01Y-113865D02*
X1274306D01*
G01X1291806D02*
Y-96365D01*
X1283727Y-108907D01*
X1294645D01*
G01X1179383Y-68865D02*
Y-51365D01*
X1183749D01*
X1185496Y-52240D01*
X1186806Y-53407D01*
X1187898Y-55156D01*
X1188771Y-57199D01*
X1188989Y-60115D01*
X1188771Y-63032D01*
X1187898Y-65074D01*
X1186806Y-66824D01*
X1185496Y-67990D01*
X1183749Y-68865D01*
X1179383D01*
G01X1205616D02*
Y-57199D01*
G01Y-59240D02*
X1204743Y-58074D01*
X1203432Y-57490D01*
X1201904Y-57199D01*
X1200376Y-57782D01*
X1199066Y-58948D01*
X1198192Y-60698D01*
X1197756Y-63032D01*
X1198192Y-65365D01*
X1199066Y-67115D01*
X1200376Y-68282D01*
X1201904Y-68865D01*
X1203432Y-68573D01*
X1204743Y-67699D01*
X1205616Y-66532D01*
G01X1219186Y-51365D02*
Y-68865D01*
G01X1216129Y-57199D02*
X1222243D01*
G01X1233411Y-60990D02*
X1240398D01*
X1239743Y-58948D01*
X1238651Y-57782D01*
X1237123Y-57199D01*
X1235594Y-57490D01*
X1234284Y-58365D01*
X1233411Y-60407D01*
X1232974Y-62157D01*
Y-63907D01*
X1233411Y-65657D01*
X1234503Y-67407D01*
X1235813Y-68573D01*
X1237341Y-68865D01*
X1238869Y-68282D01*
X1240398Y-66532D01*
G01X371950Y92500D02*
X370200Y90750D01*
Y77069D01*
X388769Y58500D01*
X416100D01*
X430700Y43900D01*
X445194D01*
X454094Y35000D01*
X484400D01*
X490600Y41200D01*
X492900D01*
X493500Y40600D01*
Y38300D01*
X494100Y37700D01*
X495300D01*
X495900Y38300D01*
Y40600D01*
X496500Y41200D01*
X498000D01*
X503200Y36000D01*
Y31007D01*
X506550Y27657D01*
X517843D01*
X526100Y19400D01*
Y14807D01*
X528358Y12549D01*
X528525D01*
G01X530700Y15407D02*
Y18307D01*
X510800Y38207D01*
Y45100D01*
X509700Y46200D01*
X507468D01*
X506868Y45600D01*
Y44100D01*
X506268Y43500D01*
X505068D01*
X504468Y44100D01*
Y45600D01*
X503868Y46200D01*
X502668D01*
X502068Y45600D01*
Y44100D01*
X501468Y43500D01*
X489500D01*
X483300Y37300D01*
X455047D01*
X446147Y46200D01*
X431653D01*
X417053Y60800D01*
X389722D01*
X371900Y78622D01*
Y85400D01*
G01X375800Y90500D02*
X373860Y88560D01*
Y79915D01*
X390675Y63100D01*
X418006D01*
X432606Y48500D01*
X447100D01*
X456000Y39600D01*
X482100D01*
X491000Y48500D01*
X513183D01*
X513783Y47900D01*
Y41400D01*
X514383Y40800D01*
X515583D01*
X516183Y41400D01*
Y47900D01*
X516783Y48500D01*
X517983D01*
X518583Y47900D01*
Y41400D01*
X519183Y40800D01*
X520383D01*
X520983Y41400D01*
Y47000D01*
X521583Y47600D01*
X523400D01*
X524000Y47000D01*
Y39500D01*
X529000Y34500D01*
Y32695D01*
X529120Y32575D01*
G01X375800Y83500D02*
Y81228D01*
X391626Y65402D01*
X418957D01*
X428059Y56300D01*
X436607D01*
X437207Y55700D01*
Y51400D01*
X437807Y50800D01*
X439007D01*
X439607Y51400D01*
Y54900D01*
X440207Y55500D01*
X441407D01*
X442007Y54900D01*
Y51400D01*
X442607Y50800D01*
X443807D01*
X444407Y51400D01*
Y55000D01*
X445007Y55600D01*
X446207D01*
X446807Y55000D01*
Y51400D01*
X447407Y50800D01*
X448607D01*
X449207Y51400D01*
Y54800D01*
X449807Y55400D01*
X450907D01*
X451507Y54800D01*
Y51400D01*
X452107Y50800D01*
X523900D01*
X526100Y48600D01*
Y41400D01*
X530892Y36608D01*
Y32254D01*
X532339Y30807D01*
X532350D01*
G01X533200Y22907D02*
X534292Y23999D01*
Y37208D01*
X528753Y42747D01*
Y53100D01*
X528153Y53700D01*
X494593D01*
X494103Y53210D01*
X492303D01*
X491813Y53700D01*
X490013D01*
X489523Y53210D01*
X487723D01*
X487233Y53700D01*
X479863D01*
X479373Y53210D01*
X477573D01*
X477083Y53700D01*
X475283D01*
X474793Y53210D01*
X472993D01*
X472503Y53700D01*
X470703D01*
X470213Y53210D01*
X468413D01*
X467923Y53700D01*
X463644D01*
X462400Y54944D01*
Y58000D01*
X461800Y58600D01*
X459007D01*
X458407Y58000D01*
Y56494D01*
X457163Y55250D01*
X455051D01*
X453807Y56494D01*
Y58599D01*
X453207Y59199D01*
X447200D01*
X446601Y58600D01*
X444800D01*
X444201Y59199D01*
X428566D01*
X420063Y67702D01*
X399798D01*
X391650Y75850D01*
X384450D01*
X377670Y82630D01*
Y88770D01*
X379500Y90600D01*
G01X542100Y15107D02*
Y19500D01*
X538900Y22700D01*
Y34000D01*
X537900Y35000D01*
Y38500D01*
X532153Y44247D01*
Y47498D01*
X532753Y48098D01*
X533900D01*
X534500Y48698D01*
Y51098D01*
X533900Y51698D01*
X532753D01*
X532153Y52298D01*
Y56500D01*
X531553Y57100D01*
X468109D01*
X462610Y62599D01*
X429975D01*
X421472Y71102D01*
X401207D01*
X393109Y79200D01*
X384800D01*
X381400Y82600D01*
Y88450D01*
X383450Y90500D01*
G01X545928Y31047D02*
X545300Y31675D01*
Y37300D01*
X546200Y38200D01*
X551000D01*
X551600Y38800D01*
Y43105D01*
X552200Y43705D01*
X554800D01*
X555400Y44305D01*
Y46705D01*
X554800Y47305D01*
X552200D01*
X551600Y47905D01*
Y52000D01*
X550649Y52951D01*
X542200D01*
X541600Y53551D01*
Y63400D01*
X541000Y64000D01*
X473700D01*
X473100Y64600D01*
Y68899D01*
X472500Y69499D01*
X432834D01*
X424330Y78003D01*
X404066D01*
X397669Y84400D01*
X392400D01*
X387200Y89600D01*
Y90500D01*
G01X536485Y22907D02*
X535392Y24000D01*
Y37664D01*
X529853Y43203D01*
Y53556D01*
X528609Y54800D01*
X464100D01*
X463500Y55400D01*
Y58456D01*
X462256Y59700D01*
X458551D01*
X457307Y58456D01*
Y56950D01*
X456707Y56350D01*
X455507D01*
X454907Y56950D01*
Y59055D01*
X453663Y60299D01*
X429022D01*
X420519Y68802D01*
X400254D01*
X392106Y76950D01*
X384906D01*
X379500Y82356D01*
Y83302D01*
G01X542407Y30882D02*
X542444Y30919D01*
X542575D01*
X543600Y31944D01*
Y34400D01*
X543000Y35000D01*
Y39800D01*
X543600Y40400D01*
X547800D01*
X548400Y41000D01*
Y42846D01*
X547800Y43446D01*
X543100D01*
X542500Y44046D01*
Y46446D01*
X543100Y47046D01*
X548500D01*
X549100Y47646D01*
Y50046D01*
X548500Y50646D01*
X539700D01*
X539100Y51246D01*
Y60700D01*
X538100Y61700D01*
X472747D01*
X470800Y63647D01*
Y65400D01*
X469001Y67199D01*
X431881D01*
X423377Y75703D01*
X403112D01*
X396015Y82800D01*
X387800D01*
X387100Y83500D01*
G01X544860Y12407D02*
Y24207D01*
X544260Y24807D01*
X542500D01*
X541500Y25807D01*
Y29000D01*
X540300Y30200D01*
Y42600D01*
X539200Y43700D01*
X536700D01*
X536100Y44300D01*
Y46900D01*
X536800Y47600D01*
Y58200D01*
X535600Y59400D01*
X469100D01*
X468500Y60000D01*
Y63700D01*
X467301Y64899D01*
X430928D01*
X422425Y73402D01*
X402160D01*
X394581Y80981D01*
X385719D01*
X383350Y83350D01*
G01X587940Y12417D02*
Y18320D01*
X577200Y29060D01*
Y35107D01*
X582100Y40007D01*
Y60355D01*
X577255Y65200D01*
X545200D01*
X543100Y67300D01*
X477000D01*
X476400Y67900D01*
Y72199D01*
X475800Y72799D01*
X434201D01*
X426800Y80200D01*
X409600D01*
G01X404400Y228600D02*
Y233200D01*
X411700Y240500D01*
X474100D01*
X489250Y255650D01*
X495850D01*
X508400Y268200D01*
X510769D01*
X511369Y267600D01*
Y264900D01*
X511969Y264300D01*
X513169D01*
X513769Y264900D01*
Y267600D01*
X514369Y268200D01*
X524626D01*
X525226Y267600D01*
Y262800D01*
X525826Y262200D01*
X527026D01*
X527626Y262800D01*
Y267600D01*
X528226Y268200D01*
X529426D01*
X530026Y267600D01*
Y262800D01*
X530626Y262200D01*
X531826D01*
X532426Y262800D01*
Y267600D01*
X533026Y268200D01*
X541100D01*
X542200Y267100D01*
Y259100D01*
X543700Y257600D01*
X547884D01*
X549984Y255500D01*
X550200D01*
G01X415800Y215900D02*
X415850D01*
X417700Y217750D01*
Y223800D01*
X419400Y225500D01*
X423300D01*
X424887Y223913D01*
X466587D01*
X468000Y222500D01*
Y221000D01*
X469100Y219900D01*
X476266D01*
X476866Y220500D01*
Y223100D01*
X477466Y223700D01*
X478666D01*
X479266Y223100D01*
Y220500D01*
X479866Y219900D01*
X481066D01*
X481666Y220500D01*
Y223313D01*
X482266Y223913D01*
X483466D01*
X484066Y223313D01*
Y220500D01*
X484666Y219900D01*
X485866D01*
X486466Y220500D01*
Y223313D01*
X487066Y223913D01*
X488266D01*
X488866Y223313D01*
Y220500D01*
X489466Y219900D01*
X526300D01*
X529600Y223200D01*
X534708D01*
X535308Y222600D01*
Y221900D01*
X535908Y221300D01*
X537108D01*
X537708Y221900D01*
Y222600D01*
X538308Y223200D01*
X546099D01*
X550399Y227500D01*
X554800D01*
X565950Y238650D01*
Y245850D01*
X564200Y247600D01*
Y254200D01*
X564666Y254666D01*
X564947D01*
X565054Y254773D01*
G01X558926Y262489D02*
X557834Y261397D01*
Y260300D01*
X558905Y259229D01*
Y244351D01*
X554430Y239876D01*
Y239183D01*
X553158Y237911D01*
X552465D01*
X551192Y236638D01*
Y235945D01*
X549919Y234672D01*
X549226D01*
X546054Y231500D01*
X534859D01*
X533359Y233000D01*
X529960D01*
X529470Y232510D01*
X527670D01*
X527180Y233000D01*
X525380D01*
X524890Y232510D01*
X523090D01*
X522600Y233000D01*
X520800D01*
X517863Y230063D01*
X506013D01*
X504769Y231307D01*
Y232900D01*
X504169Y233500D01*
X502969D01*
X502369Y232900D01*
Y231307D01*
X501125Y230063D01*
X497913D01*
X496669Y231307D01*
Y234600D01*
X496069Y235200D01*
X494869D01*
X494269Y234600D01*
Y231307D01*
X493025Y230063D01*
X490913D01*
X489669Y231307D01*
Y234600D01*
X489069Y235200D01*
X487869D01*
X487269Y234600D01*
Y231307D01*
X486025Y230063D01*
X417019D01*
X413950Y226994D01*
G01X408200Y226900D02*
Y229900D01*
X414063Y235763D01*
X476363D01*
X482896Y242296D01*
X494496D01*
X502400Y250200D01*
Y254100D01*
X503000Y254700D01*
X504700D01*
X505300Y254100D01*
Y250500D01*
X505900Y249900D01*
X508867D01*
X509467Y250500D01*
Y253600D01*
X510067Y254200D01*
X511267D01*
X511867Y253600D01*
Y250500D01*
X512467Y249900D01*
X534400D01*
X538600Y245700D01*
X550300D01*
X555200Y250600D01*
Y255700D01*
X549437Y261463D01*
Y264765D01*
X548837Y265365D01*
X546900D01*
X546300Y265965D01*
Y267165D01*
X546900Y267765D01*
X548837D01*
X549437Y268365D01*
Y270363D01*
X548800Y271000D01*
G01X555641Y262489D02*
X556734Y261396D01*
Y259844D01*
X557805Y258773D01*
Y244807D01*
X545598Y232600D01*
X535315D01*
X533815Y234100D01*
X520344D01*
X517407Y231163D01*
X506469D01*
X505869Y231763D01*
Y233356D01*
X504625Y234600D01*
X502513D01*
X501269Y233356D01*
Y231763D01*
X500669Y231163D01*
X498369D01*
X497769Y231763D01*
Y235056D01*
X496525Y236300D01*
X494413D01*
X493169Y235056D01*
Y231763D01*
X492569Y231163D01*
X491369D01*
X490769Y231763D01*
Y235056D01*
X489525Y236300D01*
X487413D01*
X486169Y235056D01*
Y231763D01*
X485569Y231163D01*
X416563D01*
X412850Y227450D01*
G01X415600Y222700D02*
Y225400D01*
X417900Y227700D01*
X424000D01*
X425487Y226213D01*
X492226D01*
X492826Y225613D01*
Y222800D01*
X493426Y222200D01*
X494626D01*
X495226Y222800D01*
Y225613D01*
X495826Y226213D01*
X497026D01*
X497626Y225613D01*
Y222800D01*
X498226Y222200D01*
X499426D01*
X500026Y222800D01*
Y225613D01*
X500626Y226213D01*
X501826D01*
X502426Y225613D01*
Y222800D01*
X503026Y222200D01*
X504226D01*
X504826Y222800D01*
Y225613D01*
X505426Y226213D01*
X506626D01*
X507226Y225613D01*
Y222800D01*
X507826Y222200D01*
X509026D01*
X509626Y222800D01*
Y225613D01*
X510226Y226213D01*
X516226D01*
X516826Y225613D01*
Y224300D01*
X517426Y223700D01*
X518626D01*
X519226Y224300D01*
Y225613D01*
X519826Y226213D01*
X524460D01*
X526047Y227800D01*
X528100D01*
X529450Y226450D01*
X546096D01*
X562300Y242654D01*
Y251610D01*
X562296Y251614D01*
Y253904D01*
X561419Y254781D01*
Y254850D01*
G01X408100Y220500D02*
X410200Y222600D01*
Y228500D01*
X415163Y233463D01*
X477400D01*
X483933Y239996D01*
X499696D01*
X502093Y242393D01*
Y246100D01*
X502693Y246700D01*
X503893D01*
X504493Y246100D01*
Y242450D01*
X505093Y241850D01*
X506293D01*
X506893Y242450D01*
Y246100D01*
X507493Y246700D01*
X508693D01*
X509293Y246100D01*
Y242450D01*
X509893Y241850D01*
X511093D01*
X511693Y242450D01*
Y246100D01*
X512293Y246700D01*
X513493D01*
X514093Y246100D01*
Y242450D01*
X514693Y241850D01*
X550350D01*
X556500Y248000D01*
Y257100D01*
X551937Y261663D01*
Y272789D01*
G01X551000Y252056D02*
X550984Y252040D01*
X550356D01*
X546727Y248411D01*
X539300D01*
X538700Y249011D01*
Y252693D01*
X538100Y253293D01*
X537000D01*
X536400Y253893D01*
Y255093D01*
X537000Y255693D01*
X539400D01*
X540000Y256293D01*
Y258500D01*
X539400Y259100D01*
X524107D01*
X523507Y258500D01*
Y257600D01*
X522907Y257000D01*
X521707D01*
X521107Y257600D01*
Y258500D01*
X520507Y259100D01*
X517500D01*
X515100Y261500D01*
X505437D01*
X497287Y253350D01*
X490587D01*
X488958Y251721D01*
Y250873D01*
X493643Y246192D01*
Y245344D01*
X492896Y244596D01*
X491844D01*
X487260Y249175D01*
X486412D01*
X485562Y248325D01*
Y247477D01*
X486746Y246294D01*
Y245446D01*
X485896Y244596D01*
X485048D01*
X483864Y245779D01*
X483016D01*
X475300Y238063D01*
X412563D01*
X406300Y231800D01*
Y224200D01*
X404400Y222300D01*
G01X594400Y36207D02*
Y70285D01*
X590485Y74200D01*
X492398D01*
X487399Y79199D01*
X484900D01*
X484300Y79799D01*
Y82100D01*
X483700Y82700D01*
X482300D01*
X481700Y82100D01*
Y80299D01*
X481100Y79699D01*
X479700D01*
X479100Y80299D01*
Y82100D01*
X478500Y82700D01*
X476600D01*
X476000Y82100D01*
Y80299D01*
X475400Y79699D01*
X473900D01*
X473300Y80299D01*
Y82100D01*
X472700Y82700D01*
X461474D01*
X460874Y82100D01*
Y80300D01*
X460274Y79700D01*
X459074D01*
X458474Y80300D01*
Y82100D01*
X457874Y82700D01*
X456674D01*
X456074Y82100D01*
Y80300D01*
X455474Y79700D01*
X454274D01*
X453674Y80300D01*
Y82100D01*
X453074Y82700D01*
X450774D01*
X450174Y82100D01*
Y80299D01*
X449574Y79699D01*
X437901D01*
X433500Y84100D01*
G01X421600Y82800D02*
X431200D01*
X436601Y77399D01*
X463174D01*
X463774Y77999D01*
Y79800D01*
X464374Y80400D01*
X465574D01*
X466174Y79800D01*
Y77999D01*
X466774Y77399D01*
X467974D01*
X468574Y77999D01*
Y79800D01*
X469174Y80400D01*
X470374D01*
X470974Y79800D01*
Y77999D01*
X471574Y77399D01*
X480800D01*
X481400Y76799D01*
Y75500D01*
X482000Y74900D01*
X483600D01*
X484200Y75500D01*
Y76200D01*
X484800Y76800D01*
X486545D01*
X487200Y76145D01*
Y72500D01*
X487800Y71900D01*
X587500D01*
X589500Y69900D01*
Y50600D01*
X590100Y50000D01*
X591200D01*
X591800Y49400D01*
Y48200D01*
X591200Y47600D01*
X590100D01*
X589500Y47000D01*
Y45800D01*
X590100Y45200D01*
X591200D01*
X591800Y44600D01*
Y43400D01*
X591200Y42800D01*
X590100D01*
X589500Y42200D01*
Y33837D01*
X589300Y33637D01*
Y33007D01*
G01X594600Y6707D02*
Y23307D01*
X587200Y30707D01*
Y58600D01*
X578300Y67500D01*
X546153D01*
X544053Y69600D01*
X484902D01*
X484302Y70200D01*
Y71500D01*
X483702Y72100D01*
X482502D01*
X481902Y71500D01*
Y70700D01*
X481302Y70100D01*
X479300D01*
X478700Y70700D01*
Y74200D01*
X477801Y75099D01*
X435154D01*
X429253Y81000D01*
G01X419600Y216200D02*
X419700Y216300D01*
X424800D01*
X427400Y218900D01*
X463300D01*
X469500Y212700D01*
X474700D01*
X476000Y214000D01*
X480700D01*
X482000Y212700D01*
X555603D01*
X573800Y230897D01*
Y258300D01*
X563835Y268265D01*
Y270835D01*
X564100Y271100D01*
G01X419550Y222700D02*
X421500D01*
X422587Y221613D01*
X464087D01*
X469100Y216600D01*
X473700D01*
X474700Y217600D01*
X483270D01*
X483870Y217000D01*
Y215600D01*
X484470Y215000D01*
X485670D01*
X486270Y215600D01*
Y217000D01*
X486870Y217600D01*
X488070D01*
X488670Y217000D01*
Y215600D01*
X489270Y215000D01*
X490470D01*
X491070Y215600D01*
Y217000D01*
X491670Y217600D01*
X492870D01*
X493470Y217000D01*
Y215600D01*
X494070Y215000D01*
X495270D01*
X495870Y215600D01*
Y217000D01*
X496470Y217600D01*
X548403D01*
X570100Y239297D01*
Y257600D01*
X561300Y266400D01*
Y269600D01*
X560600Y270300D01*
G01X436100Y85700D02*
X437400D01*
X438100Y85000D01*
X440600D01*
X443200Y82400D01*
X446256D01*
X448856Y85000D01*
X484851D01*
X493351Y76500D01*
X591438D01*
X597300Y70638D01*
Y31567D01*
X602797Y26070D01*
Y24000D01*
X601704Y22907D01*
G01X436556Y86800D02*
X437856D01*
X438556Y86100D01*
X441056D01*
X443656Y83500D01*
X445800D01*
X448400Y86100D01*
X485307D01*
X493807Y77600D01*
X591894D01*
X598400Y71094D01*
Y69294D01*
X598890Y68804D01*
Y67004D01*
X598400Y66514D01*
Y63038D01*
X598890Y62548D01*
Y60748D01*
X598400Y60258D01*
Y56466D01*
X598890Y55976D01*
Y54176D01*
X598400Y53686D01*
Y51700D01*
X598890Y51210D01*
Y49410D01*
X598400Y48920D01*
Y47120D01*
X598890Y46630D01*
Y44830D01*
X598400Y44340D01*
Y42540D01*
X598890Y42050D01*
Y40250D01*
X598400Y39760D01*
Y32023D01*
X599343Y31080D01*
X600036D01*
X601309Y29807D01*
Y29114D01*
X603897Y26526D01*
Y23999D01*
X604989Y22907D01*
G01X607300Y14507D02*
Y18607D01*
X607514Y18821D01*
Y25786D01*
X603700Y29600D01*
Y32800D01*
X601400Y35100D01*
Y71347D01*
X592847Y79900D01*
X494760D01*
X485660Y89000D01*
X437600D01*
X437000Y88400D01*
G01X610944Y33333D02*
Y41044D01*
X612800Y42900D01*
Y44809D01*
X612200Y45409D01*
X611544D01*
X610944Y46009D01*
Y47209D01*
X611544Y47809D01*
X612800D01*
X613400Y48409D01*
Y49609D01*
X612800Y50209D01*
X611544D01*
X610944Y50809D01*
Y52009D01*
X611544Y52609D01*
X612200D01*
X612800Y53209D01*
Y54409D01*
X612200Y55009D01*
X611544D01*
X610944Y55609D01*
Y56809D01*
X611544Y57409D01*
X612200D01*
X612800Y58009D01*
Y59209D01*
X612200Y59809D01*
X611544D01*
X610944Y60409D01*
Y61609D01*
X611544Y62209D01*
X612200D01*
X612800Y62809D01*
Y64009D01*
X612200Y64609D01*
X611544D01*
X610944Y65209D01*
Y66409D01*
X611544Y67009D01*
X612200D01*
X612800Y67609D01*
Y68809D01*
X612200Y69409D01*
X611544D01*
X610944Y70009D01*
Y72309D01*
X596453Y86800D01*
X507919D01*
X507900Y86819D01*
X497600D01*
X487810Y96609D01*
X435009D01*
G01X436500Y94309D02*
X486857D01*
X496666Y84500D01*
X595500D01*
X606100Y73900D01*
Y66866D01*
X606700Y66266D01*
X607700D01*
X608300Y65666D01*
Y64466D01*
X607700Y63866D01*
X606700D01*
X606100Y63266D01*
Y62066D01*
X606700Y61466D01*
X607700D01*
X608300Y60866D01*
Y59666D01*
X607700Y59066D01*
X606700D01*
X606100Y58466D01*
Y57266D01*
X606700Y56666D01*
X607700D01*
X608300Y56066D01*
Y54866D01*
X607700Y54266D01*
X606700D01*
X606100Y53666D01*
Y52200D01*
X607700Y50600D01*
Y48900D01*
X606100Y47300D01*
Y37500D01*
X609260Y34340D01*
Y32467D01*
X607800Y31007D01*
Y30407D01*
G01X610952Y12307D02*
X609100Y14159D01*
Y15607D01*
X610200Y16707D01*
Y25600D01*
X605800Y30000D01*
Y33900D01*
X603800Y35900D01*
Y72200D01*
X593800Y82200D01*
X495713D01*
X486222Y91691D01*
X437200D01*
G01X436800Y135700D02*
X465800D01*
X467159Y134341D01*
X513860D01*
X519428Y128771D01*
X550900D01*
X551500Y128171D01*
Y126567D01*
X552167Y125900D01*
X574300D01*
X574900Y126500D01*
Y128171D01*
X575500Y128771D01*
X577800D01*
X578400Y128171D01*
Y126500D01*
X579000Y125900D01*
X580200D01*
X580800Y126500D01*
Y128171D01*
X581400Y128771D01*
X582600D01*
X583200Y128171D01*
Y126700D01*
X583800Y126100D01*
X585000D01*
X585600Y126700D01*
Y128171D01*
X586200Y128771D01*
X620099D01*
X640165Y108705D01*
Y104177D01*
X641277Y103065D01*
X644282D01*
X650700Y96647D01*
Y92047D01*
X652047Y90700D01*
X658170D01*
X709100Y39770D01*
Y32941D01*
X707198Y31039D01*
Y28707D01*
X710498Y25407D01*
X710500D01*
Y21107D01*
X715120Y16487D01*
X724400D01*
X727880Y13007D01*
Y12987D01*
X728010Y12857D01*
G01X437306Y148800D02*
X437906Y148200D01*
X440200D01*
X441459Y146941D01*
X610100D01*
X621745Y144946D01*
X719695Y46996D01*
X730950Y38250D01*
X735000Y34200D01*
X735600Y32107D01*
X737148Y28678D01*
X738781Y22218D01*
Y19181D01*
X736800Y17200D01*
Y15007D01*
X737400Y14407D01*
X739000D01*
G01X742200Y12407D02*
X740766Y19939D01*
X738131Y29832D01*
X736800Y32407D01*
X736095Y34872D01*
X729287Y42247D01*
X720922Y49022D01*
X622873Y147071D01*
X611620Y149241D01*
X452700D01*
X446914Y149862D01*
X443287Y150700D01*
X437100D01*
G01X435700Y137500D02*
X467883D01*
X468742Y136641D01*
X515806D01*
X517647Y134800D01*
X519947D01*
X520547Y134200D01*
Y131671D01*
X521147Y131071D01*
X522347D01*
X522947Y131671D01*
Y133500D01*
X523547Y134100D01*
X525300D01*
X525900Y133500D01*
Y131671D01*
X526500Y131071D01*
X528100D01*
X528700Y131671D01*
Y133500D01*
X529300Y134100D01*
X531500D01*
X532100Y133500D01*
Y131671D01*
X532700Y131071D01*
X553145D01*
X553745Y130471D01*
Y128800D01*
X554345Y128200D01*
X555545D01*
X556145Y128800D01*
Y130471D01*
X556745Y131071D01*
X564878D01*
X565478Y130471D01*
Y128800D01*
X566078Y128200D01*
X567278D01*
X567878Y128800D01*
Y130471D01*
X568478Y131071D01*
X569678D01*
X570549Y130200D01*
X572407D01*
X573278Y131071D01*
X621052D01*
X714400Y37723D01*
Y29287D01*
X723480Y20207D01*
X726400D01*
X731169Y15438D01*
Y14584D01*
G01X740200Y29907D02*
Y38285D01*
X723885Y54600D01*
X718597D01*
X621047Y152150D01*
X444950D01*
X444000Y153100D01*
G01X742100Y33007D02*
Y40400D01*
X725400Y57100D01*
X723200D01*
X655704Y124005D01*
X623309Y156400D01*
X446400D01*
G01X690102Y12502D02*
X689905D01*
X684500Y17907D01*
X675300D01*
X674700Y18507D01*
Y26907D01*
X675300Y27507D01*
X677060D01*
X677660Y28107D01*
Y38963D01*
X675108Y41515D01*
X674260D01*
X673298Y40552D01*
X672449D01*
X671598Y41401D01*
Y42249D01*
X672562Y43213D01*
Y44061D01*
X671712Y44911D01*
X670864D01*
X669502Y43547D01*
X668654D01*
X667803Y44397D01*
Y45245D01*
X669166Y46609D01*
Y47457D01*
X657323Y59300D01*
X639803D01*
X596633Y102470D01*
X492573D01*
X483702Y111341D01*
X460359D01*
X453000Y118700D01*
G01X692200Y15357D02*
Y18153D01*
X689846Y20507D01*
X686300D01*
X685700Y21107D01*
Y25307D01*
X685100Y25907D01*
X681000D01*
X679600Y27307D01*
Y40276D01*
X658276Y61600D01*
X642800D01*
X638912Y65488D01*
Y66336D01*
X640514Y67938D01*
Y68786D01*
X639664Y69636D01*
X638816D01*
X637214Y68034D01*
X636366D01*
X635516Y68884D01*
Y69732D01*
X637118Y71334D01*
Y72182D01*
X636268Y73032D01*
X635420D01*
X633818Y71430D01*
X632970D01*
X611420Y92980D01*
X610572D01*
X610398Y92806D01*
X609550D01*
X608700Y93656D01*
Y94504D01*
X608874Y94678D01*
Y95526D01*
X608024Y96376D01*
X607176D01*
X607002Y96202D01*
X606154D01*
X605304Y97052D01*
Y97900D01*
X605478Y98074D01*
Y98922D01*
X604628Y99772D01*
X603780D01*
X603606Y99598D01*
X602758D01*
X601908Y100448D01*
Y101296D01*
X602082Y101470D01*
Y102318D01*
X599630Y104770D01*
X493526D01*
X484655Y113641D01*
X464959D01*
X459800Y118800D01*
G01X689624Y30383D02*
X688504D01*
X684300Y34587D01*
Y36500D01*
X683214Y37586D01*
Y39915D01*
X659229Y63900D01*
X649047D01*
X646970Y65976D01*
X646122D01*
X644397Y64251D01*
X643549D01*
X642700Y65100D01*
Y65948D01*
X644424Y67673D01*
Y68521D01*
X642253Y70693D01*
X636763Y76183D01*
X631470D01*
X624849Y82804D01*
Y83652D01*
X626574Y85378D01*
Y86226D01*
X625724Y87076D01*
X624876D01*
X623151Y85350D01*
X622303D01*
X620673Y86980D01*
Y87828D01*
X622398Y89554D01*
Y90402D01*
X621547Y91252D01*
X620699D01*
X618975Y89526D01*
X618127D01*
X617277Y90376D01*
Y91224D01*
X619052Y93000D01*
Y93848D01*
X618202Y94698D01*
X617354D01*
X615579Y92922D01*
X614731D01*
X604362Y103291D01*
Y106138D01*
X603430Y107070D01*
X494479D01*
X485608Y115941D01*
X465959D01*
X462300Y119600D01*
G01X732806Y23607D02*
X733900Y24701D01*
Y25507D01*
X733200Y26207D01*
Y27107D01*
X733900Y27807D01*
Y29007D01*
X726253Y36654D01*
X725228D01*
X620182Y141700D01*
X587244D01*
X585403Y143541D01*
X581353D01*
X580753Y142941D01*
Y139944D01*
X579509Y138700D01*
X577397D01*
X576153Y139944D01*
Y142941D01*
X575553Y143541D01*
X566597D01*
X564756Y141700D01*
X555744D01*
X553903Y143541D01*
X548837D01*
X548347Y143051D01*
X546547D01*
X546057Y143541D01*
X544257D01*
X543767Y143051D01*
X541967D01*
X541477Y143541D01*
X539677D01*
X539187Y143051D01*
X537387D01*
X536897Y143541D01*
X535097D01*
X533256Y141700D01*
X521644D01*
X519803Y143541D01*
X463100D01*
G01X736091Y23607D02*
X735000Y24698D01*
Y29463D01*
X726709Y37754D01*
X725684D01*
X620638Y142800D01*
X587700D01*
X585859Y144641D01*
X580897D01*
X579653Y143397D01*
Y140400D01*
X579053Y139800D01*
X577853D01*
X577253Y140400D01*
Y143397D01*
X576009Y144641D01*
X566141D01*
X564300Y142800D01*
X556200D01*
X554359Y144641D01*
X534641D01*
X532800Y142800D01*
X522100D01*
X520259Y144641D01*
X463050D01*
G01X463941Y141241D02*
X518850D01*
X519344Y140747D01*
Y140746D01*
X520690Y139400D01*
X534209D01*
X535560Y140751D01*
X537149D01*
X538500Y139400D01*
X540000D01*
X541351Y140751D01*
X542349D01*
X543700Y139400D01*
X545009D01*
X546360Y140751D01*
X547560D01*
X548911Y139400D01*
X550300D01*
X551596Y140696D01*
X553495D01*
X554791Y139400D01*
X573500D01*
X574100Y138800D01*
Y136271D01*
X574700Y135671D01*
X583053D01*
X583653Y136271D01*
Y138800D01*
X584253Y139400D01*
X585453D01*
X586053Y138800D01*
Y136271D01*
X586653Y135671D01*
X587853D01*
X588453Y136271D01*
Y138800D01*
X589053Y139400D01*
X590253D01*
X590853Y138800D01*
Y136271D01*
X591453Y135671D01*
X592653D01*
X593253Y136271D01*
Y138800D01*
X593853Y139400D01*
X605653D01*
X606253Y138800D01*
Y136271D01*
X606853Y135671D01*
X608053D01*
X608653Y136271D01*
Y138800D01*
X609253Y139400D01*
X610453D01*
X611053Y138800D01*
Y137100D01*
X611653Y136500D01*
X612853D01*
X613453Y137100D01*
Y138800D01*
X614053Y139400D01*
X619229D01*
X622957Y135671D01*
X622958D01*
X723475Y35154D01*
X725553D01*
X730400Y30307D01*
Y30007D01*
X730500Y29907D01*
G01X463700Y139300D02*
X468391D01*
X468750Y138941D01*
X516759D01*
X518600Y137100D01*
X534429D01*
X535129Y136400D01*
Y133971D01*
X535729Y133371D01*
X536929D01*
X537529Y133971D01*
Y136400D01*
X538129Y137000D01*
X539329D01*
X539929Y136400D01*
Y133971D01*
X540529Y133371D01*
X541729D01*
X542329Y133971D01*
Y136400D01*
X542929Y137000D01*
X544129D01*
X544729Y136400D01*
Y133971D01*
X545329Y133371D01*
X546529D01*
X547129Y133971D01*
Y136400D01*
X547729Y137000D01*
X548929D01*
X549529Y136400D01*
Y133971D01*
X550129Y133371D01*
X595553D01*
X596153Y133971D01*
Y136500D01*
X596753Y137100D01*
X597953D01*
X598553Y136500D01*
Y133971D01*
X599153Y133371D01*
X600353D01*
X600953Y133971D01*
Y136500D01*
X601553Y137100D01*
X602753D01*
X603353Y136500D01*
Y133971D01*
X603953Y133371D01*
X615457D01*
X616057Y133971D01*
Y135300D01*
X616657Y135900D01*
X617857D01*
X618457Y135300D01*
Y133971D01*
X619057Y133371D01*
X622005D01*
X716300Y39076D01*
Y30537D01*
X720030Y26807D01*
X723500D01*
X727000Y30307D01*
Y30407D01*
G01X685100Y273100D02*
Y271176D01*
X696500Y259776D01*
Y222894D01*
X658407Y184801D01*
Y180107D01*
X640000Y161700D01*
X459900D01*
X454200Y167400D01*
G01X461200D02*
X464600Y164000D01*
X639047D01*
X656107Y181060D01*
Y185754D01*
X692420Y222067D01*
Y248880D01*
X692200Y249100D01*
Y253220D01*
X693900Y254920D01*
Y259601D01*
X682801Y270700D01*
X682481D01*
G01X466300Y120541D02*
X487514D01*
X496385Y111670D01*
X608268D01*
X643238Y76700D01*
X652200D01*
X652800Y76100D01*
Y74200D01*
X652200Y73600D01*
X650944D01*
X649700Y72356D01*
Y69844D01*
X650944Y68600D01*
X661035D01*
X691635Y38000D01*
X694144D01*
X695400Y36744D01*
Y25551D01*
X696000Y24951D01*
Y23807D01*
X695046Y22853D01*
X695029D01*
G01X693300Y30607D02*
X693100D01*
X690450Y33257D01*
Y36650D01*
X689117Y37983D01*
X688399D01*
X660182Y66200D01*
X650000D01*
X636265Y79935D01*
X635417D01*
X634574Y79092D01*
X633726D01*
X632876Y79942D01*
Y80790D01*
X633319Y81233D01*
Y82081D01*
X632469Y82931D01*
X631621D01*
X630569Y81879D01*
X629721D01*
X628871Y82729D01*
Y83577D01*
X630323Y85029D01*
Y85877D01*
X617798Y98402D01*
X616950D01*
X615152Y96604D01*
X614304D01*
X613454Y97454D01*
Y98302D01*
X615252Y100100D01*
Y100948D01*
X614402Y101798D01*
X613554D01*
X611756Y100000D01*
X610908D01*
X610058Y100850D01*
Y101698D01*
X611856Y103496D01*
Y104344D01*
X611006Y105194D01*
X610158D01*
X608360Y103396D01*
X607512D01*
X606662Y104246D01*
Y105094D01*
X608460Y106892D01*
Y107740D01*
X606830Y109370D01*
X495432D01*
X486561Y118241D01*
X466359D01*
G01X468219Y124081D02*
X500419D01*
X507850Y116650D01*
X513320D01*
X514900Y115070D01*
X609677D01*
X644647Y80100D01*
X654344D01*
X693744Y40700D01*
X695100D01*
X698080Y37720D01*
Y27127D01*
X702000Y23207D01*
Y12607D01*
G01X468159Y128741D02*
X511538D01*
X517107Y123171D01*
X518978Y121300D01*
X522300D01*
X524171Y123171D01*
X537629D01*
X540500Y120300D01*
X541700D01*
X542300Y120900D01*
Y122571D01*
X542900Y123171D01*
X544100D01*
X544700Y122571D01*
Y120900D01*
X545300Y120300D01*
X591300D01*
X592400Y121400D01*
X605900D01*
X607500Y119800D01*
X615700D01*
X620380Y115120D01*
X621228D01*
X621703Y115594D01*
X622551D01*
X623401Y114744D01*
Y113896D01*
X622575Y113072D01*
Y112225D01*
X623425Y111375D01*
X624274D01*
X625099Y112198D01*
X625947D01*
X626797Y111348D01*
Y110500D01*
X626322Y110025D01*
Y109178D01*
X644063Y91437D01*
Y90764D01*
X649727Y85100D01*
X655850D01*
X701600Y39350D01*
Y35500D01*
X702600Y34500D01*
Y31607D01*
X701800Y30807D01*
G01X704430Y33313D02*
X704300Y33443D01*
Y39904D01*
X696505Y47699D01*
X696504D01*
X656803Y87400D01*
X650680D01*
X647400Y90680D01*
Y94400D01*
X646500Y95300D01*
X644700D01*
X643800Y96200D01*
Y98880D01*
X642915Y99765D01*
X639910D01*
X636100Y103575D01*
Y105300D01*
X634471Y106929D01*
X633623D01*
X633198Y106504D01*
X632350D01*
X631500Y107354D01*
Y108202D01*
X631925Y108627D01*
Y109475D01*
X619400Y122000D01*
X616500D01*
X613029Y125471D01*
X607171D01*
X605400Y123700D01*
X602800D01*
X601029Y125471D01*
X598371D01*
X596600Y123700D01*
X591447D01*
X590347Y122600D01*
X549500D01*
X546629Y125471D01*
X518060D01*
X512492Y131041D01*
X468259D01*
G01X467759Y126441D02*
X510517D01*
X519588Y117370D01*
X610630D01*
X645400Y82600D01*
X655097D01*
X695197Y42500D01*
X696200D01*
X699260Y39440D01*
Y28647D01*
X703850Y24057D01*
Y15537D01*
X704872Y14515D01*
X705031D01*
G01X467759Y121641D02*
X487970D01*
X496841Y112770D01*
X498641D01*
X499131Y113260D01*
X500931D01*
X501421Y112770D01*
X503221D01*
X503711Y113260D01*
X505511D01*
X506001Y112770D01*
X507801D01*
X508291Y113260D01*
X510091D01*
X510581Y112770D01*
X608724D01*
X643694Y77800D01*
X652656D01*
X653900Y76556D01*
Y73744D01*
X652656Y72500D01*
X651400D01*
X650800Y71900D01*
Y70300D01*
X651400Y69700D01*
X661491D01*
X692091Y39100D01*
X694600D01*
X696500Y37200D01*
Y26007D01*
X697100Y25407D01*
Y24003D01*
X698248Y22855D01*
X698277D01*
G01X685382Y252200D02*
X685900Y251682D01*
Y248300D01*
X686500Y247700D01*
X689520D01*
X690120Y247100D01*
Y232998D01*
X682074Y224952D01*
Y224104D01*
X683815Y222364D01*
Y221516D01*
X682965Y220666D01*
X682117D01*
X680376Y222406D01*
X679528D01*
X678678Y221556D01*
Y220708D01*
X680419Y218968D01*
Y218120D01*
X679569Y217270D01*
X678721D01*
X676980Y219010D01*
X676132D01*
X675282Y218160D01*
Y217312D01*
X677023Y215572D01*
Y214724D01*
X676173Y213874D01*
X675325D01*
X673584Y215614D01*
X672736D01*
X671886Y214764D01*
Y213916D01*
X673627Y212176D01*
Y211328D01*
X672777Y210478D01*
X671929D01*
X670188Y212218D01*
X669340D01*
X667711Y210589D01*
Y208989D01*
X671050Y205650D01*
Y203950D01*
X653807Y186707D01*
Y182013D01*
X638094Y166300D01*
X466200D01*
G01X479200Y181200D02*
X480323D01*
X480923Y181800D01*
Y182600D01*
X481523Y183200D01*
X482723D01*
X483323Y182600D01*
Y181800D01*
X483923Y181200D01*
X485123D01*
X485723Y181800D01*
Y182600D01*
X486323Y183200D01*
X487523D01*
X488123Y182600D01*
Y181800D01*
X488723Y181200D01*
X489923D01*
X490523Y181800D01*
Y182600D01*
X491123Y183200D01*
X492323D01*
X492923Y182600D01*
Y181800D01*
X493523Y181200D01*
X594000D01*
X595900Y183100D01*
Y185300D01*
X598772Y188172D01*
Y189020D01*
X598206Y189586D01*
Y190434D01*
X599056Y191284D01*
X599904D01*
X600478Y190710D01*
X601326D01*
X602176Y191560D01*
Y192408D01*
X601659Y192925D01*
Y193773D01*
X605686Y197800D01*
X611800D01*
X614400Y195200D01*
X617800D01*
X618400Y195800D01*
Y198100D01*
X619000Y198700D01*
X623150D01*
X623750Y198100D01*
Y196700D01*
X624350Y196100D01*
X638300D01*
X638900Y196700D01*
Y200100D01*
X638300Y200700D01*
X630700D01*
X630100Y201300D01*
Y202952D01*
X630700Y203552D01*
X638907D01*
X641551Y206196D01*
Y207044D01*
X640972Y207624D01*
Y208472D01*
X641822Y209322D01*
X642669D01*
X643249Y208742D01*
X644097D01*
X644947Y209592D01*
Y210440D01*
X644368Y211020D01*
Y211868D01*
X645218Y212718D01*
X646065D01*
X646645Y212138D01*
X647493D01*
X648343Y212988D01*
Y213836D01*
X647764Y214416D01*
Y215264D01*
X648614Y216114D01*
X649461D01*
X650041Y215534D01*
X650889D01*
X651739Y216384D01*
Y217232D01*
X651160Y217812D01*
Y218660D01*
X652010Y219510D01*
X652857D01*
X653437Y218930D01*
X654285D01*
X656608Y221253D01*
Y222101D01*
X655992Y222717D01*
Y223565D01*
X656842Y224415D01*
X657690D01*
X658306Y223799D01*
X659154D01*
X660004Y224649D01*
Y225497D01*
X659388Y226113D01*
Y226961D01*
X660238Y227811D01*
X661086D01*
X661702Y227195D01*
X662550D01*
X663400Y228045D01*
Y228893D01*
X662784Y229509D01*
Y230357D01*
X663634Y231207D01*
X664482D01*
X665098Y230591D01*
X665946D01*
X666796Y231441D01*
Y232289D01*
X666180Y232905D01*
Y233753D01*
X668600Y236173D01*
Y245200D01*
X671580Y248180D01*
Y253170D01*
X670200Y254550D01*
Y254700D01*
G01X673770Y254752D02*
X672900Y253882D01*
Y245300D01*
X671100Y243500D01*
Y232492D01*
X641207Y202599D01*
Y194366D01*
X639741Y192900D01*
X638400D01*
X637500Y193800D01*
X636300D01*
X635700Y193200D01*
Y189000D01*
X635100Y188400D01*
X633827D01*
X633227Y189000D01*
Y193200D01*
X632627Y193800D01*
X631427D01*
X630827Y193200D01*
Y188900D01*
X630227Y188300D01*
X629027D01*
X628427Y188900D01*
Y193200D01*
X627827Y193800D01*
X626627D01*
X626027Y193200D01*
Y188900D01*
X625427Y188300D01*
X623300D01*
X622700Y188900D01*
Y194300D01*
X622100Y194900D01*
X621000D01*
X620400Y194300D01*
Y188900D01*
X619800Y188300D01*
X618700D01*
X618100Y188900D01*
Y192300D01*
X617500Y192900D01*
X616300D01*
X615700Y192300D01*
Y188900D01*
X615100Y188300D01*
X612100D01*
X611500Y188900D01*
Y194847D01*
X610847Y195500D01*
X607500D01*
X606380Y194380D01*
Y190981D01*
X605454Y190055D01*
X604255D01*
X602986Y188786D01*
Y185686D01*
X602200Y184900D01*
X599700D01*
X598400Y183600D01*
Y182200D01*
X595100Y178900D01*
X477900D01*
G01X682800Y254900D02*
X683550Y254150D01*
Y245600D01*
X684150Y245000D01*
X687300D01*
X687900Y244400D01*
Y243041D01*
X687300Y242441D01*
X684200D01*
X683600Y241841D01*
Y240641D01*
X684200Y240041D01*
X687300D01*
X687900Y239441D01*
Y238241D01*
X687300Y237641D01*
X684200D01*
X683600Y237041D01*
Y235841D01*
X684200Y235241D01*
X686600D01*
X687200Y234641D01*
Y233441D01*
X686600Y232841D01*
X684200D01*
X683600Y232241D01*
Y229731D01*
X659079Y205210D01*
Y204362D01*
X661096Y202344D01*
Y201496D01*
X660246Y200646D01*
X659398D01*
X657381Y202664D01*
X656533D01*
X655683Y201814D01*
Y200966D01*
X657400Y199248D01*
Y198400D01*
X656550Y197550D01*
X655702D01*
X653985Y199268D01*
X653137D01*
X651507Y197638D01*
Y183005D01*
X649170Y180668D01*
Y180629D01*
X637141Y168600D01*
X465900D01*
G01X475500Y176600D02*
X598700D01*
X608050Y185950D01*
X610626D01*
X611226Y185350D01*
Y184300D01*
X611826Y183700D01*
X613026D01*
X613626Y184300D01*
Y185350D01*
X614226Y185950D01*
X615426D01*
X616026Y185350D01*
Y184300D01*
X616626Y183700D01*
X617826D01*
X618426Y184300D01*
Y185350D01*
X619026Y185950D01*
X620226D01*
X620826Y185350D01*
Y184300D01*
X621426Y183700D01*
X622626D01*
X623226Y184300D01*
Y185350D01*
X623826Y185950D01*
X625026D01*
X625626Y185350D01*
Y184300D01*
X626226Y183700D01*
X627426D01*
X628026Y184300D01*
Y185350D01*
X628626Y185950D01*
X629826D01*
X630426Y185350D01*
Y184300D01*
X631026Y183700D01*
X632226D01*
X632826Y184300D01*
Y185350D01*
X633426Y185950D01*
X636044D01*
X638000Y187906D01*
Y189700D01*
X638600Y190300D01*
X640394D01*
X643507Y193413D01*
Y201646D01*
X674330Y232469D01*
Y242540D01*
X676290Y244500D01*
Y255970D01*
X670481Y261779D01*
X669000D01*
X668400Y262379D01*
Y263579D01*
X669000Y264179D01*
X671000D01*
X671600Y264779D01*
Y265979D01*
X671000Y266579D01*
X669000D01*
X668400Y267179D01*
Y267900D01*
X669000Y268500D01*
X671000D01*
X671600Y269100D01*
Y270400D01*
X671000Y271000D01*
X669800D01*
X669700Y270900D01*
G01X679398Y262489D02*
X678306Y261397D01*
Y260350D01*
X680230Y258426D01*
Y251270D01*
X681300Y250200D01*
Y231377D01*
X672513Y222590D01*
Y221897D01*
X671240Y220624D01*
X670547D01*
X669275Y219352D01*
Y218659D01*
X668002Y217386D01*
X667309D01*
X666036Y216113D01*
Y215420D01*
X664763Y214147D01*
X664070D01*
X649207Y199284D01*
Y184651D01*
X647716Y183160D01*
Y182467D01*
X646443Y181194D01*
X645750D01*
X644477Y179921D01*
Y179228D01*
X643204Y177955D01*
X642511D01*
X641239Y176683D01*
Y175990D01*
X639966Y174717D01*
X639273D01*
X635456Y170900D01*
X625444D01*
X624200Y172144D01*
Y177000D01*
X623600Y177600D01*
X622400D01*
X621800Y177000D01*
Y172144D01*
X620556Y170900D01*
X618444D01*
X617200Y172144D01*
Y177000D01*
X616600Y177600D01*
X615400D01*
X614800Y177000D01*
Y172144D01*
X613556Y170900D01*
X467269D01*
G01X467442Y172000D02*
X613100D01*
X613700Y172600D01*
Y177456D01*
X614944Y178700D01*
X617056D01*
X618300Y177456D01*
Y172600D01*
X618900Y172000D01*
X620100D01*
X620700Y172600D01*
Y177456D01*
X621944Y178700D01*
X624056D01*
X625300Y177456D01*
Y172600D01*
X625900Y172000D01*
X635000D01*
X648107Y185107D01*
Y199740D01*
X680200Y231833D01*
Y249744D01*
X679130Y250814D01*
Y257970D01*
X677206Y259894D01*
Y261396D01*
X676113Y262489D01*
G01X672800Y272700D02*
X673200Y272300D01*
Y270771D01*
X674282Y269689D01*
X680200D01*
X680800Y269089D01*
Y267500D01*
X680200Y266900D01*
X674209D01*
X673609Y266300D01*
Y261091D01*
X677740Y256960D01*
Y232626D01*
X645807Y200693D01*
Y192460D01*
X634747Y181400D01*
X611400D01*
X610800Y180800D01*
Y174900D01*
X610200Y174300D01*
X609100D01*
X608500Y174900D01*
Y180800D01*
X607900Y181400D01*
X606800D01*
X606200Y180800D01*
Y174900D01*
X605600Y174300D01*
X603700D01*
X602577Y175423D01*
X600776D01*
X599653Y174300D01*
X475100D01*
G01X665500Y252189D02*
X663900D01*
X663300Y252789D01*
Y255000D01*
X662700Y255600D01*
X660150D01*
X659550Y255000D01*
Y249150D01*
X657500Y247100D01*
Y239500D01*
X632500Y214500D01*
X605825D01*
X604824Y215500D01*
X597310D01*
X596710Y214900D01*
Y213700D01*
X596110Y213100D01*
X594910D01*
X594310Y213700D01*
Y214900D01*
X593710Y215500D01*
X592510D01*
X591910Y214900D01*
Y213700D01*
X591310Y213100D01*
X590110D01*
X589510Y213700D01*
Y214900D01*
X588910Y215500D01*
X584900D01*
X584100Y214700D01*
Y209900D01*
X586050Y207950D01*
Y206550D01*
X582430Y202930D01*
Y200821D01*
X578709Y197100D01*
X576802D01*
X574400Y199500D01*
X573111D01*
X567375Y193764D01*
X474764D01*
G01X652233Y262489D02*
X651093Y261349D01*
Y259250D01*
X656960Y253383D01*
Y249480D01*
X655200Y247720D01*
Y240453D01*
X631547Y216800D01*
X606778D01*
X605028Y218550D01*
X600750D01*
X600000Y217800D01*
X582100D01*
X581100Y216800D01*
Y210991D01*
X577311Y207202D01*
Y206354D01*
X580130Y203534D01*
Y201774D01*
X578635Y200279D01*
X576875D01*
X574056Y203099D01*
X573208D01*
X566173Y196064D01*
X468600D01*
G01X648948Y262489D02*
X649993Y261444D01*
Y258794D01*
X655860Y252927D01*
Y249936D01*
X654100Y248176D01*
Y240909D01*
X652827Y239636D01*
X652134D01*
X650861Y238363D01*
Y237670D01*
X649589Y236398D01*
X648896D01*
X647623Y235125D01*
Y234432D01*
X646350Y233159D01*
X645657D01*
X644384Y231886D01*
Y231193D01*
X640807Y227616D01*
X640114D01*
X638841Y226343D01*
Y225650D01*
X637568Y224377D01*
X636875D01*
X635602Y223104D01*
Y222411D01*
X634330Y221139D01*
X633637D01*
X632364Y219866D01*
Y219173D01*
X631091Y217900D01*
X607234D01*
X605484Y219650D01*
X600294D01*
X599544Y218900D01*
X595384D01*
X594894Y219390D01*
X593094D01*
X592604Y218900D01*
X590804D01*
X590314Y219390D01*
X588514D01*
X588024Y218900D01*
X586224D01*
X585734Y219390D01*
X583934D01*
X583444Y218900D01*
X581644D01*
X580000Y217256D01*
Y211447D01*
X576211Y207658D01*
Y205898D01*
X579030Y203078D01*
Y202230D01*
X578179Y201379D01*
X577331D01*
X574512Y204199D01*
X572752D01*
X565717Y197164D01*
X468008D01*
G01X659500Y274000D02*
Y272000D01*
X664800Y266700D01*
Y258500D01*
X667180Y256120D01*
Y250480D01*
X662603Y245903D01*
Y238097D01*
X634406Y209900D01*
X623400D01*
X621850Y208350D01*
Y207150D01*
X620500Y205800D01*
X599900D01*
X586600Y192500D01*
X572617D01*
X569217Y189100D01*
X477800D01*
G01X477700Y186500D02*
X583853D01*
X598678Y201325D01*
X603588D01*
X604263Y202000D01*
X624000D01*
X629600Y207600D01*
X635359D01*
X665644Y237885D01*
Y245744D01*
X668280Y248380D01*
Y259720D01*
X666437Y261563D01*
Y271363D01*
X665100Y272700D01*
G01X475164Y191464D02*
X568328D01*
X571664Y194800D01*
X581200D01*
X585237Y198837D01*
X586085D01*
X587337Y197585D01*
X588185D01*
X589035Y198435D01*
Y199283D01*
X587333Y200985D01*
Y201833D01*
X588183Y202683D01*
X589031D01*
X590733Y200981D01*
X591581D01*
X592431Y201831D01*
Y202679D01*
X590629Y204481D01*
Y205329D01*
X591479Y206179D01*
X592327D01*
X594129Y204377D01*
X594977D01*
X595827Y205227D01*
Y206075D01*
X594075Y207827D01*
Y208675D01*
X594925Y209525D01*
X595773D01*
X597525Y207773D01*
X598373D01*
X599223Y208623D01*
Y209471D01*
X597971Y210723D01*
Y211571D01*
X599600Y213200D01*
X603871D01*
X604872Y212200D01*
X607247D01*
X607847Y211600D01*
Y209600D01*
X608447Y209000D01*
X609647D01*
X610247Y209600D01*
Y211600D01*
X610847Y212200D01*
X612047D01*
X612647Y211600D01*
Y209600D01*
X613247Y209000D01*
X614447D01*
X615047Y209600D01*
Y211600D01*
X615647Y212200D01*
X616847D01*
X617447Y211600D01*
Y209600D01*
X618047Y209000D01*
X619247D01*
X619847Y209600D01*
Y211600D01*
X620447Y212200D01*
X633453D01*
X659437Y238184D01*
Y246389D01*
G01X642937Y273089D02*
X642390Y272542D01*
Y269786D01*
X642900Y269276D01*
Y265600D01*
X643500Y265000D01*
Y260600D01*
X642900Y260000D01*
Y257800D01*
X643800Y256900D01*
X647040D01*
X649700Y254240D01*
Y249826D01*
X649100Y249226D01*
X647900D01*
X647300Y248626D01*
Y247426D01*
X647900Y246826D01*
X649100D01*
X649700Y246226D01*
Y243815D01*
X632442Y226557D01*
X631200D01*
X630600Y227157D01*
Y228000D01*
X630000Y228600D01*
X628800D01*
X628200Y228000D01*
Y226200D01*
X627600Y225600D01*
X625940D01*
X625340Y225000D01*
Y223100D01*
X624740Y222500D01*
X623540D01*
X622940Y223100D01*
Y223650D01*
X622340Y224250D01*
X621140D01*
X620540Y223650D01*
Y223100D01*
X619940Y222500D01*
X618740D01*
X618140Y223100D01*
Y223650D01*
X617540Y224250D01*
X616340D01*
X615740Y223650D01*
Y223100D01*
X615140Y222500D01*
X613940D01*
X613340Y223100D01*
Y223650D01*
X612740Y224250D01*
X611540D01*
X610940Y223650D01*
Y223100D01*
X610340Y222500D01*
X609140D01*
X608540Y223100D01*
Y223650D01*
X607940Y224250D01*
X579692D01*
X565100Y209658D01*
Y206800D01*
X560064Y201764D01*
X467164D01*
G01X467364Y199464D02*
X564764D01*
X566732Y201432D01*
Y202280D01*
X565707Y203305D01*
Y204153D01*
X566557Y205003D01*
X567405D01*
X568430Y203978D01*
X569278D01*
X570128Y204828D01*
Y205676D01*
X568726Y207078D01*
Y207926D01*
X569576Y208776D01*
X570424D01*
X571826Y207374D01*
X572674D01*
X573524Y208224D01*
Y209072D01*
X571222Y211374D01*
Y212222D01*
X572072Y213072D01*
X572920D01*
X575222Y210770D01*
X576070D01*
X577700Y212400D01*
Y219005D01*
X580645Y221950D01*
X606437D01*
X608187Y220200D01*
X629338D01*
X651900Y242762D01*
Y254640D01*
X646423Y260117D01*
Y265913D01*
X646900Y266390D01*
Y270800D01*
X646360Y271340D01*
Y271530D01*
G01X642802Y252186D02*
Y243423D01*
X632579Y233200D01*
X596500D01*
X592150Y228850D01*
X577786D01*
X560500Y211564D01*
Y208900D01*
X558700Y207100D01*
X546700D01*
X544400Y209400D01*
X518600D01*
X518000Y208800D01*
Y207500D01*
X517400Y206900D01*
X516200D01*
X515600Y207500D01*
Y208800D01*
X515000Y209400D01*
X513447D01*
X512847Y208800D01*
Y206964D01*
X512247Y206364D01*
X508912D01*
X508312Y206964D01*
Y208800D01*
X507712Y209400D01*
X506512D01*
X505912Y208800D01*
Y206964D01*
X505312Y206364D01*
X504112D01*
X503512Y206964D01*
Y208800D01*
X502912Y209400D01*
X501712D01*
X501112Y208800D01*
Y206964D01*
X500512Y206364D01*
X499312D01*
X498712Y206964D01*
Y208800D01*
X498112Y209400D01*
X496912D01*
X496312Y208800D01*
Y206964D01*
X495712Y206364D01*
X494512D01*
X493912Y206964D01*
Y208800D01*
X493312Y209400D01*
X492112D01*
X491512Y208800D01*
Y206964D01*
X490912Y206364D01*
X489712D01*
X489112Y206964D01*
Y208800D01*
X488512Y209400D01*
X487312D01*
X486712Y208800D01*
Y206964D01*
X486112Y206364D01*
X484912D01*
X484312Y206964D01*
Y208800D01*
X483712Y209400D01*
X482512D01*
X481912Y208800D01*
Y206964D01*
X481312Y206364D01*
X480112D01*
X479512Y206964D01*
Y208800D01*
X478912Y209400D01*
X477712D01*
X477112Y208800D01*
Y206964D01*
X476512Y206364D01*
X475312D01*
X474712Y206964D01*
Y208800D01*
X474112Y209400D01*
X472912D01*
X472312Y208800D01*
Y206964D01*
X471712Y206364D01*
X470512D01*
X469912Y206964D01*
Y208800D01*
X469312Y209400D01*
X468112D01*
X467512Y208800D01*
Y207912D01*
X465964Y206364D01*
G01X466564Y204064D02*
X519700D01*
X520300Y204664D01*
Y206500D01*
X520900Y207100D01*
X522200D01*
X522800Y206500D01*
Y204664D01*
X523400Y204064D01*
X524747D01*
X525347Y204664D01*
Y206500D01*
X525947Y207100D01*
X527147D01*
X527747Y206500D01*
Y204664D01*
X528347Y204064D01*
X529547D01*
X530147Y204664D01*
Y206500D01*
X530747Y207100D01*
X531947D01*
X532547Y206500D01*
Y204664D01*
X533147Y204064D01*
X534347D01*
X534947Y204664D01*
Y206500D01*
X535547Y207100D01*
X536747D01*
X537347Y206500D01*
Y204664D01*
X537947Y204064D01*
X539147D01*
X539747Y204664D01*
Y205700D01*
X540347Y206300D01*
X541547D01*
X542147Y205700D01*
Y204664D01*
X542747Y204064D01*
X559111D01*
X562800Y207753D01*
Y210611D01*
X578739Y226550D01*
X595353D01*
X595953Y227150D01*
Y229400D01*
X596553Y230000D01*
X597753D01*
X598353Y229400D01*
Y227150D01*
X598953Y226550D01*
X603200D01*
X603800Y227150D01*
Y230300D01*
X604400Y230900D01*
X605600D01*
X606200Y230300D01*
Y227150D01*
X606800Y226550D01*
X608000D01*
X608600Y227150D01*
Y230300D01*
X609200Y230900D01*
X610400D01*
X611000Y230300D01*
Y227150D01*
X611600Y226550D01*
X617690D01*
X618290Y227150D01*
Y228300D01*
X618890Y228900D01*
X620090D01*
X620690Y228300D01*
Y227150D01*
X621290Y226550D01*
X623450D01*
X627800Y230900D01*
X633532D01*
X645293Y242661D01*
Y253503D01*
X645920Y254130D01*
G54D14*
X457913Y45276D03*
X477913D03*
G54D24*
G01X29400Y180000D02*
Y182400D01*
X31800Y184800D01*
X45515D01*
X49700Y188985D01*
Y195385D01*
X51700Y197385D01*
Y234300D01*
X48100Y237900D01*
Y264700D01*
X48050Y264750D01*
Y271101D01*
X49899Y272950D01*
X64250D01*
X64700Y272500D01*
G01X26500Y181800D02*
Y182600D01*
X29700Y185800D01*
X45100D01*
X48700Y189400D01*
Y195800D01*
X50700Y197800D01*
Y233885D01*
X47100Y237485D01*
Y264000D01*
X46800Y264300D01*
Y271715D01*
X50585Y275500D01*
X66500D01*
X66800Y275200D01*
G01X144500Y158900D02*
X146800Y161200D01*
X150866D01*
X153750Y164084D01*
Y168561D01*
X161989Y176800D01*
X168800D01*
X175509Y183509D01*
X179490D01*
X193681Y197700D01*
X199600D01*
X207634Y205734D01*
Y206197D01*
X214362Y212925D01*
X217276D01*
X232275Y227924D01*
Y244382D01*
X238118Y250225D01*
X257225D01*
X262250Y255250D01*
X268916D01*
X275541Y248625D01*
X347225D01*
X348475Y249875D01*
X365350D01*
G01D02*
X365375Y249850D01*
Y226918D01*
X361725Y223267D01*
Y198081D01*
X360069Y196425D01*
X360056D01*
X358357Y194726D01*
Y186765D01*
X358400Y186722D01*
Y185478D01*
X358300Y185378D01*
Y168688D01*
X356400Y166788D01*
Y159000D01*
X358500Y156900D01*
Y155700D01*
G01X365350Y249875D02*
X373475Y258000D01*
X389234D01*
X398550Y267316D01*
Y278625D01*
X401500Y281575D01*
X434025D01*
X438600Y277000D01*
Y272540D01*
X440740Y270400D01*
X449635D01*
X452500Y273265D01*
Y275200D01*
G54D15*
G01X137300Y158900D02*
X143800Y152400D01*
X145300D01*
X147808Y149892D01*
Y145208D01*
G01X262131Y100959D02*
X265241D01*
X266975Y99225D01*
Y99075D01*
X275900Y90150D01*
Y88200D01*
G01X278075Y116475D02*
Y105525D01*
X286500Y97100D01*
X296600D01*
X300400Y93300D01*
X301600D01*
G01X379300Y275300D02*
X369575Y285025D01*
X313825D01*
X308900Y280100D01*
Y277400D01*
X304187Y272687D01*
X268389D01*
X267702Y272000D01*
X267700D01*
X267000Y271300D01*
G01X361500Y149500D02*
X361114D01*
X357700Y146086D01*
Y143307D01*
X356067Y141674D01*
X354617D01*
X353560Y142731D01*
Y160130D01*
X353750Y160320D01*
Y170250D01*
X352200Y171800D01*
G01X377476Y149688D02*
Y148476D01*
X376100Y147100D01*
X373000D01*
X370712Y149388D01*
Y152388D01*
X366150Y156950D01*
Y161150D01*
X362850Y164450D01*
Y166850D01*
X363250Y167250D01*
Y170371D01*
X359450Y174171D01*
Y183875D01*
X359550Y183975D01*
Y187175D01*
X359507Y187218D01*
Y194249D01*
X360532Y195274D01*
X360545D01*
X363277Y198006D01*
Y223192D01*
X367400Y227316D01*
Y244870D01*
X373030Y250500D01*
X405681D01*
X415800Y260619D01*
Y272568D01*
X416128Y272896D01*
G54D25*
G01X211900Y253000D02*
Y260471D01*
X206871Y265500D01*
X184671D01*
X169671Y280500D01*
X109129D01*
X102229Y273600D01*
X81858D01*
X79858Y271600D01*
X79771D01*
X78500Y270329D01*
Y260600D01*
X78700Y260400D01*
Y259800D01*
G01X217000Y252900D02*
X213900Y256000D01*
Y261300D01*
X207700Y267500D01*
X185500D01*
X170500Y282500D01*
X108300D01*
X101400Y275600D01*
X81029D01*
X79029Y273600D01*
X78942D01*
X76300Y270958D01*
Y260900D01*
X75300Y259900D01*
G01X102000Y203200D02*
X95200D01*
X92598Y200598D01*
X85898D01*
G01X97100Y189200D02*
X104000Y196100D01*
Y204200D01*
X106260Y206460D01*
X108569D01*
X110529Y204500D01*
X120619D01*
X132845Y216726D01*
X208855D01*
X211629Y219500D01*
X212500D01*
G01X102000Y203200D02*
Y205029D01*
X105431Y208460D01*
X109398D01*
X111358Y206500D01*
X119790D01*
X132016Y218726D01*
X208026D01*
X208800Y219500D01*
G54D16*
G01X377300Y140282D02*
X382917D01*
X385195Y142560D01*
Y145295D01*
X388900Y149000D01*
Y165746D01*
X383693Y170953D01*
Y171424D01*
G54D26*
G01X23100Y181800D02*
X28025Y186725D01*
X44716D01*
X47775Y189784D01*
Y214275D01*
X49775Y216275D01*
Y233501D01*
X46175Y237101D01*
Y261125D01*
X39100Y268200D01*
Y272100D01*
X43425Y276425D01*
X65514D01*
X66064Y276975D01*
X67536D01*
X68911Y275600D01*
X78200D01*
G01X150000Y210100D02*
X147212Y212888D01*
X131942D01*
X120527Y201473D01*
X114556D01*
X95583Y182500D01*
X34150D01*
X33150Y181500D01*
G01X33500Y178100D02*
X36050Y180650D01*
X96350D01*
X115323Y199623D01*
X121294D01*
X132709Y211038D01*
X146062D01*
X149200Y207900D01*
X151400D01*
X153500Y210000D01*
G01X97900Y76200D02*
Y76283D01*
X115850Y94233D01*
Y119614D01*
X124725Y128489D01*
Y150492D01*
X123150Y152067D01*
Y167516D01*
X128775Y173141D01*
Y191928D01*
X141172Y204325D01*
X143046D01*
X146396Y207675D01*
G01X94500Y76200D02*
X95200D01*
X114000Y95000D01*
Y125500D01*
X122875Y134375D01*
Y149725D01*
X121300Y151300D01*
Y168417D01*
X126925Y174042D01*
Y192907D01*
X141909Y207891D01*
X142997D01*
G01X466500Y272800D02*
X460289D01*
X458625Y274464D01*
Y276174D01*
X447900Y286900D01*
X313000D01*
X306700Y280600D01*
Y277852D01*
X303410Y274562D01*
X254621D01*
X245700Y265641D01*
Y255525D01*
X244175Y254000D01*
X232824D01*
X223000Y244176D01*
Y223989D01*
X216511Y217500D01*
X212140D01*
X209591Y214951D01*
X163540D01*
X151064Y202475D01*
X141939D01*
X130625Y191161D01*
Y172225D01*
X125000Y166600D01*
Y152883D01*
X129987Y147896D01*
Y141060D01*
X131026Y140021D01*
X134160D01*
X136156Y138025D01*
G01X130300Y135000D02*
X131775Y136475D01*
X134522D01*
X134747Y136250D01*
X149387D01*
X161125Y147988D01*
Y153525D01*
X163700Y156100D01*
Y166200D01*
X167550Y170050D01*
X171682D01*
X172632Y171000D01*
X181457D01*
X182706Y172249D01*
Y179606D01*
X192400Y189300D01*
X195361D01*
X198861Y192800D01*
X200959D01*
X212059Y203900D01*
Y204363D01*
X216196Y208500D01*
X219110D01*
X243310Y232700D01*
X251700D01*
X267275Y248275D01*
Y253400D01*
G01X133786Y134700D02*
X150030D01*
X165250Y149920D01*
Y164377D01*
X166848Y165975D01*
X170975D01*
X174450Y169450D01*
X182100D01*
X184256Y171606D01*
Y176756D01*
X192536Y185036D01*
X203497D01*
X204536Y186075D01*
Y189919D01*
X204700Y190083D01*
Y194348D01*
X213609Y203257D01*
Y203720D01*
X214648Y204759D01*
X217562D01*
X243953Y231150D01*
X252343D01*
X269800Y248607D01*
Y250700D01*
G01X131762Y141796D02*
X133466Y143500D01*
X136183D01*
X139184Y140499D01*
X140716D01*
X140717Y140500D01*
X151586D01*
X159275Y148189D01*
Y153025D01*
X156725Y155575D01*
Y162556D01*
X165669Y171500D01*
X170953D01*
X172685Y173232D01*
Y174496D01*
X178539Y180350D01*
X180699D01*
X194949Y194600D01*
X200708D01*
X210609Y204501D01*
Y204964D01*
X215595Y209950D01*
X218509D01*
X241125Y232566D01*
Y244351D01*
X242399Y245625D01*
X261825D01*
X265500Y249300D01*
G01X150804Y158896D02*
Y146927D01*
X150819Y146912D01*
Y144401D01*
X148768Y142350D01*
X139950D01*
X133300Y149000D01*
X131500D01*
G01X144995Y57995D02*
Y62895D01*
X168574Y86474D01*
Y97702D01*
X172700Y101828D01*
Y106789D01*
X172300Y107189D01*
G01X153000Y67800D02*
X176225Y91025D01*
Y98036D01*
X177264Y99075D01*
X180156D01*
X180576Y98656D01*
X181732Y97500D01*
G01X263600Y252700D02*
X258800Y247900D01*
X239200D01*
X236700Y245400D01*
Y230192D01*
X217908Y211400D01*
X214994D01*
X209159Y205565D01*
Y205102D01*
X200157Y196100D01*
X194238D01*
X179938Y181800D01*
X176000D01*
X170100Y175900D01*
X166817D01*
X155275Y164358D01*
Y151250D01*
X157500Y149025D01*
G01X140800Y158900D02*
X145025Y163125D01*
X150064D01*
X151825Y164886D01*
Y169359D01*
X161375Y178909D01*
Y189926D01*
X173574Y202125D01*
X181070D01*
X182245Y203300D01*
X195925D01*
X198198Y205573D01*
Y206374D01*
G01X263600Y239850D02*
X263550D01*
X253300Y229600D01*
X244785D01*
X216360Y201175D01*
X213720D01*
X206250Y193705D01*
Y189440D01*
X206086Y189276D01*
Y185432D01*
X204140Y183486D01*
X196486D01*
X188075Y175075D01*
Y171575D01*
X180675Y164175D01*
X167672D01*
X167581Y164084D01*
G01X440600Y274300D02*
Y278200D01*
X435300Y283500D01*
X400560D01*
X396625Y279565D01*
Y268114D01*
X388436Y259925D01*
X353875D01*
X345075Y251125D01*
X275764D01*
X269714Y257175D01*
X261452D01*
X256427Y252150D01*
X235349D01*
X227500Y244301D01*
Y225872D01*
X217278Y215650D01*
X212907D01*
X210358Y213101D01*
X204925D01*
X198198Y206374D01*
G01X446100Y18700D02*
X445575Y19225D01*
X425015D01*
X417600Y26640D01*
Y44033D01*
X412394Y49239D01*
X385028D01*
X383525Y47736D01*
Y47041D01*
X381059Y44575D01*
X379440D01*
X378225Y43360D01*
Y42190D01*
X375410Y39375D01*
X374706D01*
X373725Y38394D01*
Y37541D01*
X372151Y35967D01*
X361753D01*
X350844Y46876D01*
X334876D01*
X334000Y46000D01*
X319000D01*
X316125Y43125D01*
X316082Y43096D01*
X259596D01*
X255925Y39425D01*
X253906D01*
X244400Y48931D01*
Y50600D01*
G01X275300Y44900D02*
X278300Y47900D01*
X284200D01*
X294350Y58050D01*
Y62833D01*
X285550Y71633D01*
Y72914D01*
X256425Y102039D01*
Y115277D01*
X253575Y118127D01*
Y161975D01*
X259537Y167937D01*
Y170548D01*
X263864Y174875D01*
X264258D01*
X270433Y181050D01*
X282650D01*
X282950Y181350D01*
G01X267456Y160156D02*
Y159173D01*
X263562Y155279D01*
Y144038D01*
X269325Y138275D01*
X287825D01*
X289500Y136600D01*
Y131600D01*
X289900Y131200D01*
X304376D01*
X306876Y128700D01*
X308700D01*
X311300Y131300D01*
Y135046D01*
X323300Y147046D01*
G01X331000Y164500D02*
X326861D01*
X326570Y164209D01*
X320315D01*
X320295Y164229D01*
X319029D01*
X311100Y156300D01*
X305500D01*
X296875Y147675D01*
X276260D01*
X274075Y149860D01*
Y156023D01*
X273900Y156198D01*
G01X327696Y146108D02*
X326395D01*
X324032Y148471D01*
X322709D01*
X322138Y147900D01*
X316700D01*
X316350Y147550D01*
Y144450D01*
X316000Y144100D01*
X314850D01*
X314500Y144450D01*
Y147550D01*
X314150Y147900D01*
X313000D01*
X312650Y147550D01*
Y144450D01*
X312300Y144100D01*
X311150D01*
X310800Y144450D01*
Y147550D01*
X310450Y147900D01*
X309300D01*
X308950Y147550D01*
Y144450D01*
X308600Y144100D01*
X307450D01*
X307100Y144450D01*
Y147550D01*
X306750Y147900D01*
X305600D01*
X305250Y147550D01*
Y144450D01*
X304900Y144100D01*
X303750D01*
X303400Y144450D01*
Y147550D01*
X303050Y147900D01*
X300000D01*
X297925Y145825D01*
X273864D01*
X270500Y149189D01*
Y156250D01*
G01X350550Y153280D02*
X350440D01*
X349119Y154601D01*
Y157677D01*
X346696Y160100D01*
X339515D01*
X338325Y161290D01*
Y162191D01*
X338322Y162194D01*
Y164928D01*
X335274Y167976D01*
X325808D01*
X325626Y168158D01*
X314158D01*
X295525Y149525D01*
X277027D01*
X276000Y150552D01*
Y156715D01*
X273475Y159240D01*
X272380D01*
G01X296531Y133061D02*
Y134336D01*
X296131Y134736D01*
X291800D01*
X291400Y135136D01*
Y137500D01*
X291800Y137900D01*
X297700D01*
X298100Y138300D01*
Y139725D01*
X297700Y140125D01*
X294215D01*
X293865Y140475D01*
Y141771D01*
X293515Y142121D01*
X292365D01*
X292015Y141771D01*
Y140475D01*
X291665Y140125D01*
X290515D01*
X290165Y140475D01*
Y141771D01*
X289815Y142121D01*
X288665D01*
X288315Y141771D01*
Y140475D01*
X287965Y140125D01*
X286815D01*
X286465Y140475D01*
Y141771D01*
X286115Y142121D01*
X284965D01*
X284615Y141771D01*
Y140475D01*
X284265Y140125D01*
X276600D01*
X276200Y140525D01*
Y141700D01*
X275800Y142100D01*
X274100D01*
X273700Y141700D01*
Y140500D01*
X273325Y140125D01*
X271750D01*
X271375Y140500D01*
Y142925D01*
X268615Y145685D01*
X268121D01*
X267219Y144783D01*
X266725D01*
X265910Y145598D01*
Y146092D01*
X266812Y146994D01*
Y147488D01*
X265412Y148888D01*
Y154512D01*
X267100Y156200D01*
G01X309500Y132925D02*
X309475D01*
X308100Y134300D01*
X305600D01*
X295929Y143971D01*
X273101D01*
X267272Y149800D01*
X267187D01*
G01X304149Y128349D02*
X303423Y129075D01*
X294875D01*
X293100Y127300D01*
X282325D01*
X280400Y129225D01*
G01X327577Y48475D02*
X322314Y53738D01*
Y55603D01*
X323236Y56525D01*
X323284D01*
X324323Y57564D01*
Y59036D01*
X323284Y60075D01*
X322351D01*
X302125Y80301D01*
Y89125D01*
X309292Y96292D01*
X315608D01*
X317375Y98059D01*
Y101104D01*
X313975Y104504D01*
Y130360D01*
X320677Y137062D01*
Y142677D01*
X322683Y144683D01*
X328287D01*
X329121Y145517D01*
Y149463D01*
X327698Y150886D01*
X309792D01*
X306961Y153717D01*
G01X309400Y82100D02*
X309600Y82300D01*
X312411D01*
X321614Y73097D01*
Y71400D01*
X326614Y66400D01*
X328293D01*
X335093Y59600D01*
X346400D01*
X361702Y44298D01*
X364600D01*
G01X424599Y31300D02*
Y31451D01*
X421211Y34839D01*
Y45232D01*
X413804Y52639D01*
X366243D01*
X356182Y62700D01*
X341000D01*
X335225Y68475D01*
Y82425D01*
X343000Y90200D01*
Y106100D01*
X348025Y111125D01*
Y123249D01*
X347200Y124074D01*
Y127900D01*
X349066Y129766D01*
Y140586D01*
X350918Y142438D01*
Y150312D01*
X348369Y152861D01*
Y157366D01*
X346635Y159100D01*
X338366D01*
X337291Y160175D01*
X336309D01*
X335167Y161317D01*
Y162215D01*
X334333Y163049D01*
X334165D01*
X332800Y164414D01*
Y164716D01*
X331591Y165925D01*
X325586D01*
X324620Y164959D01*
X323438D01*
X323418Y164979D01*
X313065D01*
X306696Y158610D01*
G01X309000Y266700D02*
Y271500D01*
X311369Y273869D01*
X346131D01*
X347025Y272975D01*
X393486D01*
X394775Y274264D01*
Y280332D01*
X399793Y285350D01*
X447257D01*
X454525Y278082D01*
Y274564D01*
X464964Y264125D01*
X480325D01*
X482400Y266200D01*
G01X363604Y41042D02*
X362765D01*
X358107Y45700D01*
X355257Y48549D01*
X345805Y58000D01*
X334500D01*
X327650Y64850D01*
X323164D01*
X313150Y74864D01*
Y78950D01*
X312400Y79700D01*
G01X329800Y150800D02*
X332221Y148379D01*
Y145630D01*
X330120Y143529D01*
X322959D01*
X322125Y142695D01*
Y138605D01*
X324116Y136614D01*
Y134516D01*
X322808Y133208D01*
X319408D01*
X317360Y131160D01*
Y105340D01*
X318900Y103800D01*
Y100016D01*
X321300Y97616D01*
Y91200D01*
X318750Y88650D01*
X313450D01*
X313000Y88200D01*
Y87350D01*
X313450Y86900D01*
X318250D01*
X318600Y86550D01*
Y85500D01*
X318250Y85150D01*
X314750D01*
X314400Y84800D01*
Y83750D01*
X314750Y83400D01*
X318250D01*
X318600Y83050D01*
Y78600D01*
X319000Y78200D01*
X327300D01*
X327700Y78600D01*
Y79840D01*
X327350Y80190D01*
X321000D01*
X320600Y80590D01*
Y81540D01*
X321000Y81940D01*
X327350D01*
X327700Y82290D01*
Y83340D01*
X327350Y83690D01*
X320900D01*
X320500Y84090D01*
Y85040D01*
X320900Y85440D01*
X327350D01*
X327700Y85790D01*
Y86840D01*
X327350Y87190D01*
X323750D01*
X323400Y87540D01*
Y88590D01*
X323750Y88940D01*
X327350D01*
X327700Y89290D01*
Y91038D01*
X327300Y91438D01*
X326162D01*
G01X322075Y100650D02*
X328375Y106950D01*
Y115575D01*
X331232Y118432D01*
Y121532D01*
X333000Y123300D01*
Y126639D01*
X332500Y127139D01*
Y133637D01*
X331000Y135137D01*
Y138793D01*
X332800Y140593D01*
Y141816D01*
X334509Y143525D01*
X337325D01*
X342815Y149015D01*
Y154331D01*
X344090Y155606D01*
Y156690D01*
G01X325081Y100631D02*
X331991Y107541D01*
Y109490D01*
X335475Y112974D01*
Y132975D01*
X336904Y134404D01*
Y136256D01*
X336939Y136291D01*
Y138819D01*
X337790Y139670D01*
X339370D01*
X344305Y144605D01*
Y153795D01*
X344300Y153800D01*
G01X333000Y158300D02*
X333800Y157500D01*
Y152750D01*
X334200Y152350D01*
X341000D01*
X341600Y151750D01*
Y149700D01*
X341000Y149100D01*
X335700D01*
X335300Y148700D01*
Y145484D01*
X334341Y144525D01*
X333613D01*
X331588Y142500D01*
Y141417D01*
X330754Y140583D01*
X329283D01*
X327800Y139100D01*
Y132400D01*
X327400Y132000D01*
X326000D01*
X325600Y131600D01*
Y129300D01*
X326000Y128900D01*
X327100D01*
X327500Y128500D01*
Y126500D01*
X326900Y125900D01*
X322600D01*
X320397Y128103D01*
X319300D01*
X318700Y127503D01*
Y125959D01*
X320559Y124100D01*
X324450D01*
X324800Y123750D01*
Y122350D01*
X324450Y122000D01*
X321450D01*
X321100Y121650D01*
Y120700D01*
X321700Y120100D01*
X327100D01*
X327700Y119500D01*
Y117850D01*
X327350Y117500D01*
X324050D01*
X323700Y117150D01*
Y116075D01*
X323350Y115725D01*
X320700D01*
X320300Y115325D01*
Y114375D01*
X320700Y113975D01*
X323350D01*
X323700Y113625D01*
Y111100D01*
X323350Y110750D01*
X319800D01*
X319400Y110350D01*
Y109500D01*
X319750Y109150D01*
X326450D01*
X326800Y108800D01*
Y107400D01*
X326450Y107050D01*
X325064D01*
X324714Y106700D01*
Y105050D01*
X324364Y104700D01*
X322964D01*
X322614Y105050D01*
Y106700D01*
X322264Y107050D01*
X319750D01*
X319400Y106700D01*
Y105100D01*
X320650Y103850D01*
Y100059D01*
X322104Y98605D01*
X325354D01*
X326400Y97559D01*
Y96659D01*
X325800Y96059D01*
X322550D01*
X322200Y95709D01*
Y94500D01*
X322800Y93900D01*
X326800D01*
X328000Y92700D01*
G01X319704Y162804D02*
X322433Y160075D01*
X333241D01*
X334450Y158866D01*
Y158010D01*
X335373Y157087D01*
X339771D01*
X340809Y158125D01*
X344671D01*
X345515Y157281D01*
Y154602D01*
X350168Y149949D01*
Y142758D01*
X345070Y137660D01*
Y111469D01*
X340925Y107324D01*
Y91325D01*
X333675Y84075D01*
Y67832D01*
X340357Y61150D01*
X355539D01*
X365600Y51089D01*
X413161D01*
X419661Y44589D01*
Y32782D01*
X424543Y27900D01*
G01X423000Y43900D02*
Y45636D01*
X414447Y54189D01*
X366886D01*
X356825Y64250D01*
X346962D01*
X340164Y71048D01*
Y84664D01*
X345948Y90448D01*
Y99318D01*
X345805Y99461D01*
Y103082D01*
X352875Y110152D01*
Y132559D01*
X353775Y133459D01*
Y138925D01*
X352140Y140560D01*
Y159360D01*
X350125Y161375D01*
Y162291D01*
X349291Y163125D01*
X341101D01*
X339748Y164478D01*
X339747D01*
G01X338470Y138177D02*
X339754Y136893D01*
Y129062D01*
X340925Y127891D01*
Y116100D01*
X338075Y113250D01*
Y104300D01*
X333425Y99650D01*
Y87125D01*
X332125Y85825D01*
Y65275D01*
X333600Y63800D01*
G01X336500Y204600D02*
X343140D01*
X352200Y195540D01*
Y190800D01*
X356900Y186100D01*
G01X424536Y34800D02*
X425000Y35264D01*
Y45829D01*
X415089Y55740D01*
X413805D01*
X413804Y55739D01*
X368161D01*
X358100Y65800D01*
X347605D01*
X341714Y71691D01*
Y83614D01*
X349100Y91000D01*
Y104296D01*
X355875Y111071D01*
Y132359D01*
X360214Y136698D01*
Y147079D01*
X361210Y148075D01*
X362091D01*
X362925Y148909D01*
Y150091D01*
X362091Y150925D01*
X360375D01*
X356900Y154400D01*
Y156800D01*
X355200Y158500D01*
Y170816D01*
X351716Y174300D01*
X347200D01*
G01X412200Y192600D02*
X411200D01*
X410000Y191400D01*
Y189800D01*
X407600Y187400D01*
X406644D01*
X405693Y186449D01*
X404349D01*
X402000Y184100D01*
Y179394D01*
X397549Y174943D01*
Y174098D01*
X396715Y173264D01*
X395787D01*
X394800Y172277D01*
Y171385D01*
X393676Y170261D01*
X392867D01*
X390137Y167531D01*
Y149347D01*
X391779Y147705D01*
Y145845D01*
X395425Y142199D01*
X402380D01*
X406889Y137690D01*
Y134211D01*
X411037Y130063D01*
Y122963D01*
X412000Y122000D01*
X412900D01*
X413100Y121800D01*
G01X412462Y126300D02*
X412200Y126562D01*
Y130800D01*
X408100Y134900D01*
Y137540D01*
X402691Y142949D01*
X397662D01*
X394629Y145982D01*
Y147027D01*
X393795Y147861D01*
X392750D01*
X390889Y149722D01*
Y162280D01*
X392424Y163815D01*
X393589D01*
X394423Y164649D01*
Y165831D01*
X394391Y165863D01*
Y167836D01*
X397650Y171095D01*
Y171967D01*
X399505Y173822D01*
Y175838D01*
X400667Y177000D01*
X405803D01*
X406733Y177930D01*
Y185633D01*
X407300Y186200D01*
X408500D01*
X411100Y188800D01*
Y189300D01*
X412100Y190300D01*
Y190400D01*
G01X397100Y181000D02*
Y181700D01*
X398876Y183476D01*
Y187276D01*
X400100Y188500D01*
Y200900D01*
X402000Y202800D01*
Y210300D01*
X400700Y211600D01*
X397700D01*
X395700Y213600D01*
G01X429500Y93800D02*
Y97623D01*
X433430Y101553D01*
X485942D01*
X498500Y88995D01*
G01X426600Y274100D02*
X434075Y266625D01*
X447692D01*
X455702Y258615D01*
X480049D01*
X486650Y265216D01*
Y267417D01*
X502909Y283676D01*
X747690D01*
X762300Y269066D01*
Y250134D01*
X727600Y215434D01*
Y187570D01*
X717380Y177350D01*
X690950D01*
X689400Y178900D01*
G01X423000Y274000D02*
Y269000D01*
X427225Y264775D01*
X446925D01*
X454935Y256765D01*
X481365D01*
X506426Y281826D01*
X746923D01*
X760450Y268299D01*
Y252227D01*
X723300Y215077D01*
Y185887D01*
X716994Y179581D01*
X716919D01*
X716538Y179200D01*
X692200D01*
X687456Y183944D01*
G01X429900Y274940D02*
Y274200D01*
X435625Y268475D01*
X448459D01*
X456469Y260465D01*
X479282D01*
X484800Y265983D01*
Y268800D01*
X501526Y285526D01*
X748457D01*
X764150Y269833D01*
Y249367D01*
X732775Y217992D01*
Y209464D01*
X729450Y206139D01*
Y186793D01*
X718156Y175499D01*
X716614D01*
X716613Y175500D01*
X689547D01*
G01X460400Y275200D02*
X464500Y279300D01*
X473728D01*
X479000Y274028D01*
Y265900D01*
G01X464000Y275200D02*
X466000Y277200D01*
X473211D01*
X475500Y274911D01*
Y265900D01*
G01X747441Y33007D02*
Y46614D01*
X747125Y46930D01*
Y71430D01*
X722125Y96430D01*
Y176825D01*
X731300Y186000D01*
Y205372D01*
X734625Y208697D01*
Y217225D01*
X766000Y248600D01*
Y270600D01*
X749224Y287376D01*
X499876D01*
X482400Y269900D01*
Y266200D01*
G01X538300Y15200D02*
X529300Y6200D01*
X502500D01*
G54D17*
G01X119600Y143300D02*
X120100Y143800D01*
Y149100D01*
X112100Y157100D01*
Y190871D01*
X114929Y193700D01*
X118589D01*
X128000Y203111D01*
Y203300D01*
G01X244759Y85200D02*
X241659Y82100D01*
X236483D01*
X231630Y77247D01*
Y70870D01*
X239100Y63400D01*
X240297D01*
G01X254600Y41100D02*
X262000Y48500D01*
X271368D01*
X278868Y56000D01*
G01X278450Y216800D02*
X284450Y222800D01*
X292950D01*
X295050Y224900D01*
X304400D01*
G01X286500Y119900D02*
Y101100D01*
X288100Y99500D01*
G01D02*
X289100Y100500D01*
X309283D01*
X311133Y98650D01*
X315950D01*
G01X304400Y88400D02*
Y80820D01*
X322345Y62875D01*
X326737D01*
X331300Y58312D01*
Y48475D01*
G01X361500Y168500D02*
X360450Y167450D01*
Y163900D01*
X363800Y160550D01*
Y156250D01*
X362850Y155300D01*
Y151850D01*
X364326Y150374D01*
Y145926D01*
X361700Y143300D01*
G01X451300Y21700D02*
X430200D01*
X430000Y21500D01*
G01X753000Y272100D02*
X745150Y279950D01*
X509950D01*
X497500Y267500D01*
Y261921D01*
X494179Y258600D01*
X492925D01*
X492914Y258598D01*
X486398D01*
X482590Y254790D01*
X422810D01*
X420500Y257100D01*
Y257800D01*
G01X682600Y114300D02*
X683600Y115300D01*
Y171400D01*
X681002Y173998D01*
Y183502D01*
X684900Y187400D01*
X686700D01*
G01X753000Y272100D02*
Y270000D01*
X750000Y267000D01*
Y259182D01*
X756500Y252682D01*
Y251502D01*
X720100Y215102D01*
Y196100D01*
X711400Y187400D01*
X686700D01*
G54D27*
G01X337421Y234524D02*
X330695Y241250D01*
X310350D01*
X308850Y239750D01*
X303089D01*
X301589Y241250D01*
X285900D01*
X284400Y239750D01*
X279239D01*
X277739Y241250D01*
X273850D01*
X256050Y223450D01*
X247339D01*
X213486Y189597D01*
Y183906D01*
X195778Y166198D01*
Y161021D01*
X189157Y154400D01*
X176961D01*
X171845Y149284D01*
Y147684D01*
X150061Y125900D01*
X145061D01*
X133001Y113840D01*
Y101236D01*
X100334Y68569D01*
X91369D01*
X86250Y63450D01*
Y55350D01*
X85300Y54400D01*
G01X336502Y233604D02*
X330156Y239950D01*
X310889D01*
X309389Y238450D01*
X302550D01*
X301050Y239950D01*
X286439D01*
X284939Y238450D01*
X278700D01*
X277200Y239950D01*
X274389D01*
X256589Y222150D01*
X253130D01*
X252290Y221310D01*
X250940D01*
X250100Y222150D01*
X247878D01*
X240351Y214623D01*
Y213435D01*
X239397Y212481D01*
X238209D01*
X237254Y211526D01*
Y210338D01*
X236300Y209384D01*
X235112D01*
X214786Y189058D01*
Y183367D01*
X197078Y165659D01*
Y160482D01*
X189696Y153100D01*
X177500D01*
X173145Y148745D01*
Y147145D01*
X167570Y141570D01*
Y140382D01*
X166615Y139428D01*
X165428D01*
X161215Y135215D01*
Y134027D01*
X160261Y133073D01*
X159073D01*
X157124Y131124D01*
Y129936D01*
X156170Y128982D01*
X154982D01*
X150600Y124600D01*
X145600D01*
X144084Y123084D01*
Y121896D01*
X143130Y120942D01*
X141942D01*
X140987Y119987D01*
Y118799D01*
X140033Y117845D01*
X138845D01*
X134301Y113301D01*
Y100697D01*
X130027Y96423D01*
Y95235D01*
X129073Y94281D01*
X127885D01*
X126930Y93326D01*
Y92138D01*
X125975Y91184D01*
X124788D01*
X100873Y67269D01*
X91908D01*
X87550Y62911D01*
Y55550D01*
X88700Y54400D01*
G01X357966Y217516D02*
X358616D01*
X359550Y218450D01*
Y219800D01*
X358710Y220640D01*
Y221990D01*
X359550Y222830D01*
Y224389D01*
X361600Y226439D01*
Y236060D01*
X352810Y244850D01*
X349610D01*
X348770Y244010D01*
X347420D01*
X346580Y244850D01*
X345230D01*
X344390Y244010D01*
X343040D01*
X342200Y244850D01*
X340850D01*
X340010Y244010D01*
X338660D01*
X337820Y244850D01*
X336470D01*
X335630Y244010D01*
X334280D01*
X333440Y244850D01*
X332090D01*
X331250Y244010D01*
X329900D01*
X329060Y244850D01*
X313792D01*
X312952Y244010D01*
X311602D01*
X310762Y244850D01*
X309412D01*
X308572Y244010D01*
X307222D01*
X306382Y244850D01*
X305032D01*
X304192Y244010D01*
X302842D01*
X302002Y244850D01*
X289541D01*
X288701Y244010D01*
X287351D01*
X286511Y244850D01*
X285161D01*
X284321Y244010D01*
X282971D01*
X282131Y244850D01*
X280781D01*
X279941Y244010D01*
X278591D01*
X277751Y244850D01*
X273889D01*
X254939Y225900D01*
X246324D01*
X216699Y196275D01*
X214075D01*
X211036Y193236D01*
Y184922D01*
X205900Y179786D01*
X199886D01*
X192747Y172647D01*
Y171013D01*
X182209Y160475D01*
X178071D01*
X169395Y151799D01*
Y148699D01*
X149046Y128350D01*
X144046D01*
X130550Y114854D01*
Y102950D01*
X98619Y71019D01*
X88819D01*
X85023Y67223D01*
Y66035D01*
X84069Y65081D01*
X82881D01*
X81500Y63700D01*
Y62364D01*
X82885Y60979D01*
G01X359827Y216341D02*
Y216788D01*
X360850Y217811D01*
Y223850D01*
X362900Y225900D01*
Y236599D01*
X353349Y246150D01*
X273350D01*
X254400Y227200D01*
X245785D01*
X216160Y197575D01*
X213536D01*
X209736Y193775D01*
Y185461D01*
X205361Y181086D01*
X199347D01*
X191447Y173186D01*
Y171552D01*
X181670Y161775D01*
X177532D01*
X168095Y152338D01*
Y149238D01*
X148507Y129650D01*
X143507D01*
X129250Y115393D01*
Y103489D01*
X98080Y72319D01*
X88280D01*
X80200Y64239D01*
Y62064D01*
X79115Y60979D01*
G01X103450Y54400D02*
X102500Y55350D01*
Y61700D01*
X103859Y63059D01*
X105047D01*
X106001Y64013D01*
Y65201D01*
X106956Y66156D01*
X108144D01*
X109098Y67110D01*
Y68298D01*
X110053Y69253D01*
X111241D01*
X112195Y70207D01*
Y71395D01*
X113350Y72550D01*
X125153D01*
X144300Y91697D01*
Y94039D01*
X142739Y95600D01*
X141285D01*
X140685Y96200D01*
Y97400D01*
X141985Y98700D01*
X145239D01*
X146900Y100361D01*
Y104939D01*
X144539Y107300D01*
X141339D01*
X140685Y107954D01*
Y113146D01*
X143739Y116200D01*
X145661D01*
X146900Y114961D01*
Y109261D01*
X148361Y107800D01*
X151220D01*
X154740Y111320D01*
Y120240D01*
X158200Y123700D01*
Y125308D01*
X159603Y126711D01*
X160791D01*
X161746Y127666D01*
Y128854D01*
X162700Y129808D01*
X163888D01*
X164843Y130763D01*
Y131951D01*
X165797Y132905D01*
X166985D01*
X167940Y133860D01*
Y135048D01*
X172442Y139550D01*
X177539D01*
X182308Y144319D01*
X183496D01*
X184450Y145274D01*
Y146461D01*
X185408Y147419D01*
X189319D01*
X198000Y156100D01*
X202100D01*
X205209Y159209D01*
X206397D01*
X207352Y160164D01*
Y161352D01*
X208306Y162306D01*
X209494D01*
X210449Y163261D01*
Y164449D01*
X213880Y167880D01*
Y175041D01*
X218586Y179747D01*
Y187554D01*
X222186Y191154D01*
X223374D01*
X224329Y192109D01*
Y193297D01*
X231900Y200868D01*
X233621D01*
X244157Y211404D01*
Y213125D01*
X248066Y217034D01*
X256777D01*
X274443Y234700D01*
X325547D01*
X334337Y225910D01*
G01X100050Y54400D02*
X101200Y55550D01*
Y62239D01*
X112811Y73850D01*
X124614D01*
X143000Y92236D01*
Y93500D01*
X142200Y94300D01*
X140746D01*
X139385Y95661D01*
Y97939D01*
X141446Y100000D01*
X144700D01*
X145600Y100900D01*
Y104400D01*
X144000Y106000D01*
X140800D01*
X139385Y107415D01*
Y113685D01*
X143200Y117500D01*
X146200D01*
X148200Y115500D01*
Y109800D01*
X148900Y109100D01*
X150681D01*
X153440Y111859D01*
Y120779D01*
X156900Y124239D01*
Y125847D01*
X171903Y140850D01*
X177000D01*
X184869Y148719D01*
X188780D01*
X197461Y157400D01*
X201561D01*
X212580Y168419D01*
Y175580D01*
X217286Y180286D01*
Y188093D01*
X231361Y202168D01*
X233082D01*
X242857Y211943D01*
Y213664D01*
X247527Y218334D01*
X256238D01*
X273904Y236000D01*
X326086D01*
X335256Y226830D01*
G01X331184Y224791D02*
X325025Y230950D01*
X282030D01*
X281190Y230110D01*
X279840D01*
X279000Y230950D01*
X277650D01*
X276800Y230100D01*
Y226400D01*
X275064Y224664D01*
X269736D01*
X267497Y222425D01*
Y221237D01*
X266543Y220283D01*
X265355D01*
X260807Y215735D01*
Y212268D01*
X258239Y209700D01*
X247757D01*
X245802Y207745D01*
Y206557D01*
X244848Y205603D01*
X243660D01*
X242705Y204648D01*
Y203460D01*
X241751Y202506D01*
X240563D01*
X239608Y201551D01*
Y200363D01*
X238654Y199409D01*
X237466D01*
X235034Y196977D01*
X233313D01*
X228768Y192432D01*
Y190333D01*
X225517Y187082D01*
X223418D01*
X222336Y186000D01*
Y178193D01*
X217630Y173487D01*
Y154499D01*
X212831Y149700D01*
X204261D01*
X203361Y150600D01*
X202239D01*
X200602Y148963D01*
X198359D01*
X193065Y143669D01*
X191000D01*
X190128Y142797D01*
Y140732D01*
X188676Y139280D01*
X186202D01*
X185059Y140423D01*
X183716D01*
X182600Y139307D01*
Y137139D01*
X185100Y134639D01*
Y132200D01*
X183550Y130650D01*
X179950D01*
X175720Y134880D01*
X174219D01*
X173506Y134167D01*
Y131754D01*
X172897Y131145D01*
Y129957D01*
X171943Y129003D01*
X170755D01*
X169800Y128048D01*
Y126860D01*
X168846Y125906D01*
X167658D01*
X166703Y124951D01*
Y123763D01*
X165749Y122809D01*
X164561D01*
X161902Y120150D01*
Y116988D01*
X162742Y116148D01*
Y114798D01*
X161902Y113958D01*
Y112608D01*
X162742Y111768D01*
Y110418D01*
X161902Y109578D01*
Y103859D01*
X160947Y102904D01*
Y101716D01*
X159993Y100762D01*
X158805D01*
X149095Y91052D01*
Y89864D01*
X148141Y88910D01*
X146953D01*
X145998Y87955D01*
Y86767D01*
X145044Y85813D01*
X143856D01*
X142901Y84858D01*
Y83670D01*
X141947Y82716D01*
X140759D01*
X126343Y68300D01*
X121539D01*
X118150Y64911D01*
Y58450D01*
X119200Y57400D01*
G01X332104Y225710D02*
X325564Y232250D01*
X277111D01*
X275500Y230639D01*
Y226939D01*
X274525Y225964D01*
X269197D01*
X259507Y216274D01*
Y212807D01*
X257700Y211000D01*
X247218D01*
X234495Y198277D01*
X232774D01*
X227468Y192971D01*
Y190872D01*
X224978Y188382D01*
X222879D01*
X221036Y186539D01*
Y178732D01*
X216330Y174026D01*
Y155038D01*
X212292Y151000D01*
X204800D01*
X203900Y151900D01*
X201700D01*
X200063Y150263D01*
X197820D01*
X192526Y144969D01*
X190461D01*
X188828Y143336D01*
Y141271D01*
X188137Y140580D01*
X186741D01*
X185598Y141723D01*
X183177D01*
X181300Y139846D01*
Y136600D01*
X183800Y134100D01*
Y132739D01*
X183011Y131950D01*
X180489D01*
X176259Y136180D01*
X173680D01*
X172206Y134706D01*
Y132293D01*
X160602Y120689D01*
Y104398D01*
X125804Y69600D01*
X121000D01*
X116850Y65450D01*
Y58450D01*
X115800Y57400D01*
G01X325421Y226594D02*
X324815Y227200D01*
X284500D01*
X275700Y218400D01*
X272958D01*
X265600Y211042D01*
Y208862D01*
X262688Y205950D01*
X251650D01*
X244450Y198750D01*
Y195479D01*
X242371Y193400D01*
X237139D01*
X227325Y183586D01*
Y178904D01*
X226086Y177665D01*
Y176639D01*
X221452Y172005D01*
Y153017D01*
X213648Y145213D01*
X199913D01*
X194800Y140100D01*
Y136427D01*
X193546Y135173D01*
Y133985D01*
X192592Y133031D01*
X191404D01*
X182196Y123823D01*
Y122635D01*
X181242Y121681D01*
X180054D01*
X179099Y120726D01*
Y119538D01*
X178144Y118583D01*
X176956D01*
X176002Y117629D01*
Y116441D01*
X175047Y115486D01*
X173859D01*
X170300Y111927D01*
Y104550D01*
X169345Y103595D01*
Y102407D01*
X168391Y101453D01*
X167203D01*
X166248Y100498D01*
Y99310D01*
X165294Y98356D01*
X164106D01*
X159400Y93650D01*
X158889D01*
X157934Y92695D01*
Y91507D01*
X156980Y90553D01*
X155792D01*
X154837Y89598D01*
Y88410D01*
X153883Y87456D01*
X152695D01*
X143091Y77852D01*
Y76664D01*
X142137Y75710D01*
X140949D01*
X139994Y74755D01*
Y73567D01*
X139040Y72613D01*
X137852D01*
X136897Y71658D01*
Y70470D01*
X135943Y69516D01*
X134755D01*
X133800Y68561D01*
Y58600D01*
X135000Y57400D01*
G01X326340Y227514D02*
X325354Y228500D01*
X283961D01*
X275161Y219700D01*
X272419D01*
X264300Y211581D01*
Y209401D01*
X262149Y207250D01*
X251111D01*
X243150Y199289D01*
Y196018D01*
X241832Y194700D01*
X236600D01*
X226025Y184125D01*
Y179443D01*
X224786Y178204D01*
Y177178D01*
X220152Y172544D01*
Y153556D01*
X213109Y146513D01*
X199374D01*
X193500Y140639D01*
Y136966D01*
X169000Y112466D01*
Y105089D01*
X158861Y94950D01*
X158350D01*
X132500Y69100D01*
Y58300D01*
X131600Y57400D01*
G01X325873Y223173D02*
X325346Y223700D01*
X313700D01*
X310900Y220900D01*
X296706D01*
X294481Y218675D01*
X286310D01*
X271085Y203450D01*
X265492D01*
X264242Y202200D01*
X257196D01*
X242796Y187800D01*
X236843D01*
X231075Y182032D01*
Y177350D01*
X229836Y176111D01*
Y175085D01*
X225202Y170451D01*
Y151463D01*
X214180Y140441D01*
Y107572D01*
X205650Y99042D01*
Y83744D01*
X198856Y76950D01*
X187964D01*
X187009Y75995D01*
Y74807D01*
X186055Y73853D01*
X184867D01*
X183214Y72200D01*
X164300D01*
X149650Y57550D01*
Y55465D01*
X150715Y54400D01*
G01X326793Y224093D02*
X326660Y224225D01*
X325885Y225000D01*
X313161D01*
X310361Y222200D01*
X296167D01*
X293942Y219975D01*
X285771D01*
X270546Y204750D01*
X264953D01*
X263703Y203500D01*
X256657D01*
X242257Y189100D01*
X236304D01*
X229775Y182571D01*
Y177889D01*
X228536Y176650D01*
Y175624D01*
X223902Y170990D01*
Y152002D01*
X212880Y140980D01*
Y108111D01*
X204350Y99581D01*
Y84283D01*
X198317Y78250D01*
X187425D01*
X182675Y73500D01*
X163761D01*
X148350Y58089D01*
Y55435D01*
X147315Y54400D01*
G01X328303Y40995D02*
X327878Y41420D01*
X325859D01*
X323400Y38961D01*
Y37561D01*
X320089Y34250D01*
X224425D01*
X223585Y33410D01*
X222235D01*
X221395Y34250D01*
X220045D01*
X219205Y33410D01*
X217855D01*
X217015Y34250D01*
X215665D01*
X214825Y33410D01*
X213475D01*
X212635Y34250D01*
X166911D01*
X164200Y36961D01*
Y38400D01*
X156525Y46075D01*
Y47375D01*
X155290Y48610D01*
G01X159060D02*
X157825Y47375D01*
Y46614D01*
X165500Y38939D01*
Y37500D01*
X167450Y35550D01*
X319550D01*
X322100Y38100D01*
Y39500D01*
X325320Y42720D01*
X330206D01*
X331931Y40995D01*
G01X170290Y49600D02*
X171525Y48365D01*
Y47174D01*
X176399Y42300D01*
X223800D01*
X226600Y39500D01*
X237539D01*
X240839Y42800D01*
X242325D01*
X242925Y42200D01*
Y41517D01*
X241765Y40357D01*
G01X316300Y220200D02*
X314300D01*
X312269Y218169D01*
X299059D01*
X295815Y214925D01*
X288064D01*
X283990Y210851D01*
Y209663D01*
X283036Y208709D01*
X281848D01*
X280893Y207754D01*
Y206566D01*
X279939Y205612D01*
X278751D01*
X272839Y199700D01*
X267046D01*
X265796Y198450D01*
X258750D01*
X250944Y190644D01*
Y189456D01*
X249990Y188502D01*
X248802D01*
X247847Y187547D01*
Y186359D01*
X246893Y185405D01*
X245705D01*
X244300Y184000D01*
Y180050D01*
X242000Y177750D01*
Y171083D01*
X233625Y162708D01*
Y149859D01*
X218213Y134447D01*
Y106301D01*
X217655Y105743D01*
Y104555D01*
X216700Y103600D01*
X215512D01*
X214558Y102646D01*
Y101458D01*
X213603Y100503D01*
X212415D01*
X209450Y97538D01*
Y95396D01*
X210290Y94556D01*
Y93206D01*
X209450Y92366D01*
Y91016D01*
X210290Y90176D01*
Y88826D01*
X209450Y87986D01*
Y86636D01*
X210290Y85796D01*
Y84446D01*
X209450Y83606D01*
Y82240D01*
X204895Y77685D01*
Y76497D01*
X203941Y75543D01*
X202753D01*
X198701Y71491D01*
X190309D01*
X187459Y68641D01*
Y63520D01*
X185689Y61750D01*
X179490D01*
X179140Y62100D01*
X177539D01*
X176339Y60900D01*
Y57521D01*
X174718Y55900D01*
X171800D01*
X169700Y58000D01*
Y61000D01*
X168340Y62360D01*
X166499D01*
X165400Y61261D01*
Y55463D01*
X166463Y54400D01*
G01X316300Y221500D02*
X313761D01*
X311730Y219469D01*
X298520D01*
X295276Y216225D01*
X287525D01*
X272300Y201000D01*
X266507D01*
X265257Y199750D01*
X258211D01*
X243000Y184539D01*
Y180589D01*
X240700Y178289D01*
Y171622D01*
X232325Y163247D01*
Y150398D01*
X216913Y134986D01*
Y106840D01*
X208150Y98077D01*
Y82779D01*
X198162Y72791D01*
X189770D01*
X186159Y69180D01*
Y64059D01*
X185150Y63050D01*
X180029D01*
X179679Y63400D01*
X177000D01*
X175039Y61439D01*
Y58060D01*
X174179Y57200D01*
X172339D01*
X171000Y58539D01*
Y61539D01*
X168879Y63660D01*
X165960D01*
X164100Y61800D01*
Y55437D01*
X163063Y54400D01*
G01X174060Y49600D02*
X172825Y48365D01*
Y47713D01*
X176938Y43600D01*
X224339D01*
X227139Y40800D01*
X237000D01*
X240300Y44100D01*
X242864D01*
X244225Y42739D01*
Y41517D01*
X245385Y40357D01*
G01X181800Y54400D02*
X181150Y55050D01*
Y56150D01*
X183000Y58000D01*
X207500D01*
X211850Y62350D01*
X215189D01*
X220400Y67561D01*
Y69700D01*
X221300Y70600D01*
X226700D01*
X228100Y72000D01*
Y76100D01*
X225000Y79200D01*
Y84300D01*
X226650Y85950D01*
X230350D01*
X233100Y88700D01*
Y90850D01*
X230650Y93300D01*
Y95940D01*
X238725Y104015D01*
Y110039D01*
X233300Y115464D01*
Y130113D01*
X238648Y135461D01*
Y146048D01*
X237375Y147321D01*
Y161154D01*
X245750Y169529D01*
Y176196D01*
X251777Y182223D01*
X254823D01*
X256900Y184300D01*
Y191061D01*
X260539Y194700D01*
X267350D01*
X268600Y195950D01*
X269983D01*
X270823Y195110D01*
X272173D01*
X273013Y195950D01*
X274363D01*
X275203Y195110D01*
X276553D01*
X277393Y195950D01*
X278643D01*
X281727Y199034D01*
X282915D01*
X283869Y199988D01*
Y201176D01*
X284824Y202131D01*
X286012D01*
X286966Y203085D01*
Y204273D01*
X287921Y205228D01*
X289109D01*
X290063Y206182D01*
Y207370D01*
X291418Y208725D01*
X294925D01*
X301761Y215561D01*
X313611D01*
X315500Y217450D01*
X316600D01*
G01Y218750D02*
X314961D01*
X313072Y216861D01*
X301222D01*
X294386Y210025D01*
X290879D01*
X278104Y197250D01*
X268061D01*
X266811Y196000D01*
X260000D01*
X255600Y191600D01*
Y184839D01*
X254284Y183523D01*
X251238D01*
X244450Y176735D01*
Y170068D01*
X236075Y161693D01*
Y146782D01*
X237348Y145509D01*
Y136000D01*
X232000Y130652D01*
Y114925D01*
X237425Y109500D01*
Y104554D01*
X229350Y96479D01*
Y92761D01*
X231800Y90311D01*
Y89239D01*
X229811Y87250D01*
X226111D01*
X223700Y84839D01*
Y78661D01*
X226800Y75561D01*
Y72539D01*
X226161Y71900D01*
X220761D01*
X219100Y70239D01*
Y68100D01*
X214650Y63650D01*
X211311D01*
X206961Y59300D01*
X182461D01*
X179850Y56689D01*
Y55250D01*
X179000Y54400D01*
G01X186865Y54300D02*
X187800Y53365D01*
Y49761D01*
X191761Y45800D01*
X233200D01*
X233751Y45249D01*
Y44217D01*
X232591Y43057D01*
G01X236211D02*
X235051Y44217D01*
Y45788D01*
X233739Y47100D01*
X192300D01*
X189100Y50300D01*
Y53700D01*
X189700Y54300D01*
G01X194075Y80360D02*
X195310Y81595D01*
Y91849D01*
X198127Y94666D01*
Y139962D01*
X200928Y142763D01*
X208037D01*
X209324Y141476D01*
Y140251D01*
X210547Y139028D01*
G01X206790Y139040D02*
X208024Y140274D01*
Y140937D01*
X207498Y141463D01*
X205847D01*
X205007Y140623D01*
X203657D01*
X202817Y141463D01*
X201467D01*
X199427Y139423D01*
Y130297D01*
X200267Y129457D01*
Y128107D01*
X199427Y127267D01*
Y125917D01*
X200267Y125077D01*
Y123727D01*
X199427Y122887D01*
Y121537D01*
X200267Y120697D01*
Y119347D01*
X199427Y118507D01*
Y117157D01*
X200267Y116317D01*
Y114967D01*
X199427Y114127D01*
Y107267D01*
X200267Y106427D01*
Y105077D01*
X199427Y104237D01*
Y102887D01*
X200267Y102047D01*
Y100697D01*
X199427Y99857D01*
Y98507D01*
X200267Y97667D01*
Y96317D01*
X199427Y95477D01*
Y94127D01*
X196610Y91310D01*
Y89383D01*
X197450Y88543D01*
Y87193D01*
X196610Y86353D01*
Y81595D01*
X197845Y80360D01*
G01X317200Y215300D02*
X316625Y214725D01*
X315061D01*
X314261Y213925D01*
X302386D01*
X294736Y206275D01*
X293761D01*
X280086Y192600D01*
X269561D01*
X265761Y188800D01*
X265000D01*
X255600Y179400D01*
X252419D01*
X249950Y176931D01*
Y170264D01*
X239825Y160139D01*
Y148336D01*
X241200Y146961D01*
Y132754D01*
X239825Y131379D01*
Y119822D01*
X248450Y111197D01*
Y90511D01*
X263136Y75825D01*
X265475D01*
X269000Y72300D01*
Y58500D01*
X268000Y57500D01*
G01X321600Y211000D02*
X321175Y210575D01*
X303536D01*
X289500Y196539D01*
Y188900D01*
X288025Y187425D01*
X275436D01*
X273061Y185050D01*
X266850D01*
X253700Y171900D01*
Y168114D01*
X246625Y161039D01*
Y119249D01*
X252200Y113674D01*
Y97154D01*
X287800Y61554D01*
Y58900D01*
X286800Y57900D01*
G01X321600Y208700D02*
X321025Y209275D01*
X304075D01*
X290800Y196000D01*
Y188361D01*
X288564Y186125D01*
X275975D01*
X273600Y183750D01*
X267389D01*
X255000Y171361D01*
Y167575D01*
X247925Y160500D01*
Y119788D01*
X253500Y114213D01*
Y97693D01*
X289100Y62093D01*
Y59000D01*
X290200Y57900D01*
G01X317200Y213100D02*
X316875Y213425D01*
X315600D01*
X314800Y212625D01*
X311145D01*
X310305Y211785D01*
X308955D01*
X308115Y212625D01*
X302925D01*
X295275Y204975D01*
X294300D01*
X280625Y191300D01*
X270100D01*
X266300Y187500D01*
X265539D01*
X256139Y178100D01*
X252958D01*
X251250Y176392D01*
Y169725D01*
X241125Y159600D01*
Y148875D01*
X242500Y147500D01*
Y132215D01*
X241125Y130840D01*
Y120361D01*
X249750Y111736D01*
Y91050D01*
X263675Y77125D01*
X266014D01*
X270300Y72839D01*
Y58200D01*
X271000Y57500D01*
G01X327216Y203902D02*
X326437D01*
X325639Y204700D01*
X308500D01*
X306900Y206300D01*
X303861D01*
X302000Y204439D01*
Y203539D01*
X293250Y194789D01*
Y184155D01*
X285905Y176810D01*
X276271D01*
X269537Y170076D01*
X267638D01*
X256050Y158488D01*
Y119550D01*
X258800Y116800D01*
X261346D01*
X265390Y112756D01*
Y105834D01*
X269700Y101524D01*
Y100204D01*
X278979Y90925D01*
X280856D01*
X283941Y87840D01*
Y84059D01*
X286400Y81600D01*
X290180D01*
X298991Y72790D01*
Y69009D01*
X301900Y66100D01*
X304300D01*
X305900Y64500D01*
Y58500D01*
X304800Y57400D01*
G01X325642Y202325D02*
Y202858D01*
X325100Y203400D01*
X321101D01*
X320261Y202560D01*
X318911D01*
X318071Y203400D01*
X316721D01*
X315881Y202560D01*
X314531D01*
X313691Y203400D01*
X312341D01*
X311501Y202560D01*
X310151D01*
X309311Y203400D01*
X307961D01*
X306361Y205000D01*
X304400D01*
X303300Y203900D01*
Y203000D01*
X294550Y194250D01*
Y183616D01*
X293595Y182661D01*
Y181473D01*
X292641Y180519D01*
X291453D01*
X290498Y179564D01*
Y178376D01*
X289544Y177422D01*
X288356D01*
X286444Y175510D01*
X276810D01*
X270076Y168776D01*
X268177D01*
X257350Y157949D01*
Y120089D01*
X259339Y118100D01*
X261885D01*
X266690Y113295D01*
Y106373D01*
X271000Y102063D01*
Y100743D01*
X279518Y92225D01*
X281395D01*
X285241Y88379D01*
Y84598D01*
X286939Y82900D01*
X290719D01*
X300291Y73329D01*
Y69548D01*
X302439Y67400D01*
X304839D01*
X307200Y65039D01*
Y58400D01*
X308200Y57400D01*
G01X323331Y196696D02*
X323300D01*
X323096Y196900D01*
X318800D01*
X316500Y199200D01*
X311339D01*
X309689Y197550D01*
X302963D01*
X299650Y194237D01*
Y180961D01*
X288439Y169750D01*
X284210D01*
X283370Y168910D01*
X282020D01*
X281180Y169750D01*
X276450D01*
X271725Y165025D01*
X269730D01*
X261100Y156395D01*
Y138200D01*
X264100Y135200D01*
Y130300D01*
X261100Y127300D01*
Y124239D01*
X262714Y122625D01*
X266264D01*
X268325Y120563D01*
Y118114D01*
X269339Y117100D01*
X271789D01*
X275350Y113539D01*
Y101888D01*
X281263Y95975D01*
X282950D01*
X288212Y90713D01*
X291987D01*
X294300Y88400D01*
Y84624D01*
X311093Y67831D01*
Y64046D01*
X312939Y62200D01*
X316725D01*
X318262Y60663D01*
Y58338D01*
X319200Y57400D01*
G01X322256Y198618D02*
X321838Y198200D01*
X319339D01*
X317039Y200500D01*
X310800D01*
X309150Y198850D01*
X302424D01*
X298350Y194776D01*
Y181500D01*
X287900Y171050D01*
X275911D01*
X271186Y166325D01*
X269191D01*
X259800Y156934D01*
Y137661D01*
X262800Y134661D01*
Y130839D01*
X259800Y127839D01*
Y123700D01*
X262175Y121325D01*
X265724D01*
X267025Y120024D01*
Y117575D01*
X268800Y115800D01*
X271250D01*
X274050Y113000D01*
Y101349D01*
X280724Y94675D01*
X282411D01*
X287674Y89412D01*
X288750D01*
X288751Y89413D01*
X291448D01*
X293000Y87861D01*
Y84085D01*
X309793Y67292D01*
Y63507D01*
X312400Y60900D01*
X316186D01*
X316962Y60124D01*
Y58562D01*
X315800Y57400D01*
G54D18*
G01X357891Y104091D02*
X354300Y100500D01*
Y82300D01*
X345089Y73089D01*
G01X477913Y45276D02*
X457913D01*
G54D19*
G01X307231Y164059D02*
X312904Y169732D01*
X323901D01*
X325969Y171800D01*
X352200D01*
M02*
